FILE_TYPE = MACRO_DRAWING;
SET COLOR_WIRE YELLOW;
SET COLOR_PROP ORANGE;
SET COLOR_DOT WHITE;
SET COLOR_ARC YELLOW;
SET COLOR_BODY GREEN;
SET COLOR_NOTE PURPLE;
SET PROP_DISPLAY VALUE;
SET PAGE_NUMBER P200;
FORCEADD 9ZXL0451EKILFT..1
(8675 6000);
FORCEPROP 1 LAST PART_NUMBER AL000451003
J 0
(8209 6868);
DISPLAY 0.723404 (8209 6868);
PAINT GREEN (8209 6868);
DISPLAY INVISIBLE (8209 6868);
FORCEPROP 2 LAST VALUE 9ZXL0451EKILFT
J 0
(8225 7050);
DISPLAY 1.021277 (8225 7050);
FORCEPROP 2 LAST PART_TYPE SMLF
J 0
(8225 7100);
DISPLAY 1.021277 (8225 7100);
FORCEPROP 1 LAST MATERIAL IC
J 0
(8209 6741);
DISPLAY 0.723404 (8209 6741);
PAINT GREEN (8209 6741);
FORCEPROP 1 LAST $LOCATION U314
J 0
(8209 7015);
DISPLAY 0.723404 (8209 7015);
PAINT GREEN (8209 7015);
FORCEPROP 0 LASTPIN (8050 5775) $PN 1
J 2
(8040 5785);
DISPLAY 0.680851 (8040 5785);
PAINT MONO (8040 5785);
FORCEPROP 0 LASTPIN (9300 6475) $PN 32
J 0
(9310 6485);
DISPLAY 0.680851 (9310 6485);
PAINT MONO (9310 6485);
FORCEPROP 0 LASTPIN (9300 6275) $PN 13
J 0
(9310 6285);
DISPLAY 0.680851 (9310 6285);
PAINT MONO (9310 6285);
FORCEPROP 0 LASTPIN (9300 6225) $PN 14
J 0
(9310 6235);
DISPLAY 0.680851 (9310 6235);
PAINT MONO (9310 6235);
FORCEPROP 0 LASTPIN (9300 6175) $PN 19
J 0
(9310 6185);
DISPLAY 0.680851 (9310 6185);
PAINT MONO (9310 6185);
FORCEPROP 0 LASTPIN (9300 6125) $PN 20
J 0
(9310 6135);
DISPLAY 0.680851 (9310 6135);
PAINT MONO (9310 6135);
FORCEPROP 0 LASTPIN (9300 6075) $PN 22
J 0
(9310 6085);
DISPLAY 0.680851 (9310 6085);
PAINT MONO (9310 6085);
FORCEPROP 0 LASTPIN (9300 6025) $PN 23
J 0
(9310 6035);
DISPLAY 0.680851 (9310 6035);
PAINT MONO (9310 6035);
FORCEPROP 0 LASTPIN (9300 5975) $PN 27
J 0
(9310 5985);
DISPLAY 0.680851 (9310 5985);
PAINT MONO (9310 5985);
FORCEPROP 0 LASTPIN (9300 5925) $PN 28
J 0
(9310 5935);
DISPLAY 0.680851 (9310 5935);
PAINT MONO (9310 5935);
FORCEPROP 0 LASTPIN (8050 6175) $PN 3
J 2
(8040 6185);
DISPLAY 0.680851 (8040 6185);
PAINT MONO (8040 6185);
FORCEPROP 0 LASTPIN (8050 6125) $PN 4
J 2
(8040 6135);
DISPLAY 0.680851 (8040 6135);
PAINT MONO (8040 6135);
FORCEPROP 0 LASTPIN (9300 5375) $PN 33
J 0
(9310 5385);
DISPLAY 0.680851 (9310 5385);
PAINT MONO (9310 5385);
FORCEPROP 0 LASTPIN (8050 5725) $PN 9
J 2
(8040 5735);
DISPLAY 0.680851 (8040 5735);
PAINT MONO (8040 5735);
FORCEPROP 0 LASTPIN (8050 5675) $PN 8
J 2
(8040 5685);
DISPLAY 0.680851 (8040 5685);
PAINT MONO (8040 5685);
FORCEPROP 0 LASTPIN (8050 5525) $PN 10
J 2
(8040 5535);
DISPLAY 0.680851 (8040 5535);
PAINT MONO (8040 5535);
FORCEPROP 0 LASTPIN (8050 5475) $PN 11
J 2
(8040 5485);
DISPLAY 0.680851 (8040 5485);
PAINT MONO (8040 5485);
FORCEPROP 0 LASTPIN (8050 5425) $PN 17
J 2
(8040 5435);
DISPLAY 0.680851 (8040 5435);
PAINT MONO (8040 5435);
FORCEPROP 0 LASTPIN (8050 5375) $PN 30
J 2
(8040 5385);
DISPLAY 0.680851 (8040 5385);
PAINT MONO (8040 5385);
FORCEPROP 0 LASTPIN (8050 5875) $PN 7
J 2
(8040 5885);
DISPLAY 0.680851 (8040 5885);
PAINT MONO (8040 5885);
FORCEPROP 0 LASTPIN (8050 5925) $PN 6
J 2
(8040 5935);
DISPLAY 0.680851 (8040 5935);
PAINT MONO (8040 5935);
FORCEPROP 0 LASTPIN (8050 6625) $PN 12
J 2
(8040 6635);
DISPLAY 0.680851 (8040 6635);
PAINT MONO (8040 6635);
FORCEPROP 0 LASTPIN (8050 6575) $PN 16
J 2
(8040 6585);
DISPLAY 0.680851 (8040 6585);
PAINT MONO (8040 6585);
FORCEPROP 0 LASTPIN (8050 6525) $PN 21
J 2
(8040 6535);
DISPLAY 0.680851 (8040 6535);
PAINT MONO (8040 6535);
FORCEPROP 0 LASTPIN (8050 6475) $PN 25
J 2
(8040 6485);
DISPLAY 0.680851 (8040 6485);
PAINT MONO (8040 6485);
FORCEPROP 0 LASTPIN (8050 6425) $PN 29
J 2
(8040 6435);
DISPLAY 0.680851 (8040 6435);
PAINT MONO (8040 6435);
FORCEPROP 0 LASTPIN (9300 6625) $PN 31
J 0
(9310 6635);
DISPLAY 0.680851 (9310 6635);
PAINT MONO (9310 6635);
FORCEPROP 0 LASTPIN (8050 6325) $PN 2
J 2
(8040 6335);
DISPLAY 0.680851 (8040 6335);
PAINT MONO (8040 6335);
FORCEPROP 0 LASTPIN (9300 5725) $PN 15
J 0
(9310 5735);
DISPLAY 0.680851 (9310 5735);
PAINT MONO (9310 5735);
FORCEPROP 0 LASTPIN (9300 5675) $PN 18
J 0
(9310 5685);
DISPLAY 0.680851 (9310 5685);
PAINT MONO (9310 5685);
FORCEPROP 0 LASTPIN (9300 5625) $PN 24
J 0
(9310 5635);
DISPLAY 0.680851 (9310 5635);
PAINT MONO (9310 5635);
FORCEPROP 0 LASTPIN (9300 5575) $PN 26
J 0
(9310 5585);
DISPLAY 0.680851 (9310 5585);
PAINT MONO (9310 5585);
FORCEPROP 0 LASTPIN (8050 6025) $PN 5
J 2
(8040 6035);
DISPLAY 0.680851 (8040 6035);
PAINT MONO (8040 6035);
FORCEPROP 1 LAST CDS_LMAN_SYM_OUTLINE -475,725,475,-725
J 0
(8675 6000);
DISPLAY 0.468085 (8675 6000);
PAINT GREEN (8675 6000);
DISPLAY INVISIBLE (8675 6000);
FORCEPROP 1 LAST NEEDS_NO_SIZE TRUE
J 0
(8675 6000);
DISPLAY 0.723404 (8675 6000);
PAINT GREEN (8675 6000);
DISPLAY INVISIBLE (8675 6000);
FORCEPROP 1 LAST PATH I1
J 0
(8675 6000);
DISPLAY 0.723404 (8675 6000);
PAINT GREEN (8675 6000);
DISPLAY INVISIBLE (8675 6000);
FORCEPROP 2 LAST CDS_LIB pure_quanta
J 0
(8675 6000);
DISPLAY INVISIBLE (8675 6000);
FORCEPROP 0 LAST CDS_LOCATION U314
J 0
(8225 7150);
DISPLAY 1.021277 (8225 7150);
DISPLAY INVISIBLE (8225 7150);
FORCEPROP 0 LAST $SEC 1
J 0
(8225 7150);
DISPLAY 0.680851 (8225 7150);
PAINT MONO (8225 7150);
DISPLAY INVISIBLE (8225 7150);
FORCEPROP 0 LAST CDS_SEC 1
J 0
(8225 7150);
DISPLAY 1.021277 (8225 7150);
DISPLAY INVISIBLE (8225 7150);
FORCEADD Q_CAP..1
(6050 7375);
FORCEPROP 1 LAST PART_NUMBER CH6101ME900
J 0
(6100 7175);
DISPLAY 0.510638 (6100 7175);
DISPLAY INVISIBLE (6100 7175);
FORCEPROP 1 LAST VOLTAGE 6.3V
J 0
(6100 7375);
DISPLAY 0.638298 (6100 7375);
FORCEPROP 1 LAST PACK_TYPE C0603
J 0
(6100 7225);
DISPLAY 0.638298 (6100 7225);
FORCEPROP 1 LAST TOLERANCE 20%
J 0
(6100 7325);
DISPLAY 0.638298 (6100 7325);
FORCEPROP 1 LAST MATERIAL X6S
J 0
(6100 7275);
DISPLAY 0.638298 (6100 7275);
FORCEPROP 1 LAST VALUE 10UF
J 0
(6100 7425);
DISPLAY 0.638298 (6100 7425);
FORCEPROP 1 LAST $LOCATION C2332
J 0
(6100 7475);
DISPLAY 0.978723 (6100 7475);
FORCEPROP 1 LASTPIN (6050 7475) $PN 1
J 0
(6060 7455);
DISPLAY 0.787234 (6060 7455);
PAINT MONO (6060 7455);
FORCEPROP 1 LASTPIN (6050 7275) $PN 2
J 0
(6060 7255);
DISPLAY 0.787234 (6060 7255);
PAINT MONO (6060 7255);
FORCEPROP 2 LAST CDS_LIB pure_quanta
J 0
(6050 7375);
DISPLAY INVISIBLE (6050 7375);
FORCEPROP 1 LAST PATH I10
J 0
(6100 7525);
DISPLAY 0.978723 (6100 7525);
PAINT WHITE (6100 7525);
DISPLAY INVISIBLE (6100 7525);
FORCEPROP 0 LAST CDS_LOCATION C2332
J 0
(6100 7525);
DISPLAY 1.021277 (6100 7525);
DISPLAY INVISIBLE (6100 7525);
FORCEPROP 0 LAST $SEC 1
J 0
(6100 7525);
DISPLAY 0.680851 (6100 7525);
PAINT MONO (6100 7525);
DISPLAY INVISIBLE (6100 7525);
FORCEPROP 0 LAST CDS_SEC 1
J 0
(6100 7525);
DISPLAY 1.021277 (6100 7525);
DISPLAY INVISIBLE (6100 7525);
FORCEADD Q_RES..1
(5650 7525);
FORCEPROP 1 LAST PART_NUMBER CS-1003F900
J 0
(5500 7600);
DISPLAY 0.510638 (5500 7600);
DISPLAY INVISIBLE (5500 7600);
FORCEPROP 1 LAST PACK_TYPE 0603LF
J 0
(5500 7650);
DISPLAY 0.510638 (5500 7650);
FORCEPROP 1 LAST TOLERANCE 1%
J 0
(5875 7525);
DISPLAY 0.638298 (5875 7525);
FORCEPROP 1 LAST MATERIAL CHIP
J 0
(5975 7525);
DISPLAY 0.638298 (5975 7525);
FORCEPROP 1 LAST VALUE 1
J 2
(5850 7525);
DISPLAY 0.638298 (5850 7525);
FORCEPROP 1 LAST WATTAGE 1/10W
J 2
(5825 7650);
DISPLAY 0.510638 (5825 7650);
FORCEPROP 1 LAST $LOCATION R4475
J 0
(5425 7525);
DISPLAY 0.638298 (5425 7525);
FORCEPROP 1 LASTPIN (5550 7525) $PN 1
J 0
(5562 7537);
DISPLAY 0.787234 (5562 7537);
PAINT MONO (5562 7537);
FORCEPROP 1 LASTPIN (5750 7525) $PN 2
J 0
(5712 7537);
DISPLAY 0.787234 (5712 7537);
PAINT MONO (5712 7537);
FORCEPROP 1 LAST PATH I11
J 0
(5600 7675);
DISPLAY 0.978723 (5600 7675);
PAINT WHITE (5600 7675);
DISPLAY INVISIBLE (5600 7675);
FORCEPROP 2 LAST CDS_LIB pure_quanta
J 0
(5650 7525);
DISPLAY INVISIBLE (5650 7525);
FORCEPROP 0 LAST CDS_LOCATION R4475
J 0
(5825 7675);
DISPLAY 1.021277 (5825 7675);
DISPLAY INVISIBLE (5825 7675);
FORCEPROP 0 LAST $SEC 1
J 0
(5825 7675);
DISPLAY 0.680851 (5825 7675);
PAINT MONO (5825 7675);
DISPLAY INVISIBLE (5825 7675);
FORCEPROP 0 LAST CDS_SEC 1
J 0
(5825 7675);
DISPLAY 1.021277 (5825 7675);
DISPLAY INVISIBLE (5825 7675);
FORCEADD UNIVERSAL_GND..1
(6400 7000);
FORCEPROP 3 LASTPIN (6400 7050) SIG_NAME GND\g
J 0
(6410 7060);
DISPLAY 0.659574 (6410 7060);
PAINT MONO (6410 7060);
DISPLAY INVISIBLE (6410 7060);
FORCEPROP 1 LAST HDL_POWER GND
J 1
(6425 6925);
DISPLAY 0.872340 (6425 6925);
PAINT GREEN (6425 6925);
DISPLAY INVISIBLE (6425 6925);
FORCEPROP 1 LAST PATH I12
J 0
(6475 7000);
DISPLAY 0.872340 (6475 7000);
PAINT AQUA (6475 7000);
DISPLAY INVISIBLE (6475 7000);
FORCEPROP 2 LAST CDS_LIB logical_power
J 0
(6400 7000);
DISPLAY INVISIBLE (6400 7000);
FORCEADD Q_CAP..1
(8600 7825);
FORCEPROP 1 LAST PART_NUMBER CH6101ME900
J 0
(8650 7625);
DISPLAY 0.510638 (8650 7625);
DISPLAY INVISIBLE (8650 7625);
FORCEPROP 1 LAST VALUE 10UF
J 0
(8650 7875);
DISPLAY 0.638298 (8650 7875);
FORCEPROP 1 LAST TOLERANCE 20%
J 0
(8650 7775);
DISPLAY 0.638298 (8650 7775);
FORCEPROP 1 LAST VOLTAGE 6.3V
J 0
(8650 7825);
DISPLAY 0.638298 (8650 7825);
FORCEPROP 1 LAST PACK_TYPE C0603
J 0
(8650 7675);
DISPLAY 0.638298 (8650 7675);
FORCEPROP 1 LAST MATERIAL X6S
J 0
(8650 7725);
DISPLAY 0.638298 (8650 7725);
FORCEPROP 1 LAST $LOCATION C2328
J 0
(8650 7925);
DISPLAY 0.978723 (8650 7925);
FORCEPROP 1 LASTPIN (8600 7925) $PN 1
J 0
(8610 7905);
DISPLAY 0.787234 (8610 7905);
PAINT MONO (8610 7905);
FORCEPROP 1 LASTPIN (8600 7725) $PN 2
J 0
(8610 7705);
DISPLAY 0.787234 (8610 7705);
PAINT MONO (8610 7705);
FORCEPROP 2 LAST CDS_LIB pure_quanta
J 0
(8600 7825);
DISPLAY INVISIBLE (8600 7825);
FORCEPROP 1 LAST PATH I17
J 0
(8650 7975);
DISPLAY 0.978723 (8650 7975);
PAINT WHITE (8650 7975);
DISPLAY INVISIBLE (8650 7975);
FORCEPROP 0 LAST CDS_LOCATION C2328
J 0
(8650 7975);
DISPLAY 1.021277 (8650 7975);
DISPLAY INVISIBLE (8650 7975);
FORCEPROP 0 LAST $SEC 1
J 0
(8650 7975);
DISPLAY 0.680851 (8650 7975);
PAINT MONO (8650 7975);
DISPLAY INVISIBLE (8650 7975);
FORCEPROP 0 LAST CDS_SEC 1
J 0
(8650 7975);
DISPLAY 1.021277 (8650 7975);
DISPLAY INVISIBLE (8650 7975);
FORCEADD UNIVERSAL_GND..1
(9975 7475);
FORCEPROP 3 LASTPIN (9975 7525) SIG_NAME GND\g
J 0
(9985 7535);
DISPLAY 0.659574 (9985 7535);
PAINT MONO (9985 7535);
DISPLAY INVISIBLE (9985 7535);
FORCEPROP 1 LAST HDL_POWER GND
J 1
(10000 7400);
DISPLAY 0.872340 (10000 7400);
PAINT GREEN (10000 7400);
DISPLAY INVISIBLE (10000 7400);
FORCEPROP 1 LAST PATH I21
J 0
(10050 7475);
DISPLAY 0.872340 (10050 7475);
PAINT AQUA (10050 7475);
DISPLAY INVISIBLE (10050 7475);
FORCEPROP 2 LAST CDS_LIB logical_power
J 0
(9975 7475);
DISPLAY INVISIBLE (9975 7475);
FORCEADD UNIVERSAL_GND..1
(9500 5075);
FORCEPROP 3 LASTPIN (9500 5125) SIG_NAME GND\g
J 0
(9510 5135);
DISPLAY 0.659574 (9510 5135);
PAINT MONO (9510 5135);
DISPLAY INVISIBLE (9510 5135);
FORCEPROP 1 LAST HDL_POWER GND
J 1
(9525 5000);
DISPLAY 0.872340 (9525 5000);
PAINT GREEN (9525 5000);
DISPLAY INVISIBLE (9525 5000);
FORCEPROP 1 LAST PATH I22
J 0
(9575 5075);
DISPLAY 0.872340 (9575 5075);
PAINT AQUA (9575 5075);
DISPLAY INVISIBLE (9575 5075);
FORCEPROP 2 LAST CDS_LIB logical_power
J 0
(9500 5075);
DISPLAY INVISIBLE (9500 5075);
FORCEADD UNIVERSAL_POWER..1
(6375 8425);
FORCEPROP 3 LASTPIN (6375 8375) SIG_NAME P3V3_9ZXL045_VDDA\g
J 0
(6385 8385);
DISPLAY 0.659574 (6385 8385);
PAINT MONO (6385 8385);
DISPLAY INVISIBLE (6385 8385);
FORCEPROP 1 LAST HDL_POWER P3V3_9ZXL045_VDDA
J 1
(6375 8475);
DISPLAY 0.872340 (6375 8475);
PAINT GREEN (6375 8475);
FORCEPROP 1 LAST PATH I23
J 0
(6425 8450);
DISPLAY 0.872340 (6425 8450);
PAINT AQUA (6425 8450);
DISPLAY INVISIBLE (6425 8450);
FORCEPROP 2 LAST CDS_LIB logical_power
J 0
(6375 8425);
DISPLAY INVISIBLE (6375 8425);
FORCEADD UNIVERSAL_POWER..1
(6400 7625);
FORCEPROP 3 LASTPIN (6400 7575) SIG_NAME P3V3_9ZXL045_VDDR\g
J 0
(6410 7585);
DISPLAY 0.659574 (6410 7585);
PAINT MONO (6410 7585);
DISPLAY INVISIBLE (6410 7585);
FORCEPROP 1 LAST HDL_POWER P3V3_9ZXL045_VDDR
J 1
(6400 7675);
DISPLAY 0.872340 (6400 7675);
PAINT GREEN (6400 7675);
FORCEPROP 1 LAST PATH I24
J 0
(6450 7650);
DISPLAY 0.872340 (6450 7650);
PAINT AQUA (6450 7650);
DISPLAY INVISIBLE (6450 7650);
FORCEPROP 2 LAST CDS_LIB logical_power
J 0
(6400 7625);
DISPLAY INVISIBLE (6400 7625);
FORCEADD UNIVERSAL_POWER..1
(9975 8175);
FORCEPROP 3 LASTPIN (9975 8125) SIG_NAME P3V3_9ZXL045_VDD\g
J 0
(9985 8135);
DISPLAY 0.659574 (9985 8135);
PAINT MONO (9985 8135);
DISPLAY INVISIBLE (9985 8135);
FORCEPROP 1 LAST HDL_POWER P3V3_9ZXL045_VDD
J 1
(9975 8225);
DISPLAY 0.872340 (9975 8225);
PAINT GREEN (9975 8225);
FORCEPROP 1 LAST PATH I25
J 0
(10025 8200);
DISPLAY 0.872340 (10025 8200);
PAINT AQUA (10025 8200);
DISPLAY INVISIBLE (10025 8200);
FORCEPROP 2 LAST CDS_LIB logical_power
J 0
(9975 8175);
DISPLAY INVISIBLE (9975 8175);
FORCEADD UNIVERSAL_POWER..1
(7625 8150);
FORCEPROP 3 LASTPIN (7625 8100) SIG_NAME P3V3\g
J 0
(7635 8110);
DISPLAY 0.659574 (7635 8110);
PAINT MONO (7635 8110);
DISPLAY INVISIBLE (7635 8110);
FORCEPROP 1 LAST HDL_POWER P3V3
J 1
(7625 8200);
DISPLAY 0.872340 (7625 8200);
PAINT GREEN (7625 8200);
FORCEPROP 2 LAST CDS_LIB logical_power
J 0
(7625 8150);
DISPLAY INVISIBLE (7625 8150);
FORCEPROP 1 LAST PATH I26
J 0
(7675 8175);
DISPLAY 0.872340 (7675 8175);
PAINT AQUA (7675 8175);
DISPLAY INVISIBLE (7675 8175);
FORCEADD UNIVERSAL_POWER..1
(9625 6900);
FORCEPROP 3 LASTPIN (9625 6850) SIG_NAME P3V3_9ZXL045_VDDA\g
J 0
(9635 6860);
DISPLAY 0.659574 (9635 6860);
PAINT MONO (9635 6860);
DISPLAY INVISIBLE (9635 6860);
FORCEPROP 1 LAST HDL_POWER P3V3_9ZXL045_VDDA
J 1
(9625 6950);
DISPLAY 0.872340 (9625 6950);
PAINT GREEN (9625 6950);
FORCEPROP 1 LAST PATH I27
J 0
(9675 6925);
DISPLAY 0.872340 (9675 6925);
PAINT AQUA (9675 6925);
DISPLAY INVISIBLE (9675 6925);
FORCEPROP 2 LAST CDS_LIB logical_power
J 0
(9625 6900);
DISPLAY INVISIBLE (9625 6900);
FORCEADD UNIVERSAL_POWER..1
(7350 6600);
FORCEPROP 3 LASTPIN (7350 6550) SIG_NAME P3V3_9ZXL045_VDDR\g
J 0
(7360 6560);
DISPLAY 0.659574 (7360 6560);
PAINT MONO (7360 6560);
DISPLAY INVISIBLE (7360 6560);
FORCEPROP 1 LAST HDL_POWER P3V3_9ZXL045_VDDR
J 1
(7350 6650);
DISPLAY 0.872340 (7350 6650);
PAINT GREEN (7350 6650);
FORCEPROP 1 LAST PATH I28
J 0
(7400 6625);
DISPLAY 0.872340 (7400 6625);
PAINT AQUA (7400 6625);
DISPLAY INVISIBLE (7400 6625);
FORCEPROP 2 LAST CDS_LIB logical_power
J 0
(7350 6600);
DISPLAY INVISIBLE (7350 6600);
FORCEADD UNIVERSAL_POWER..1
(7750 6900);
FORCEPROP 3 LASTPIN (7750 6850) SIG_NAME P3V3_9ZXL045_VDD\g
J 0
(7760 6860);
DISPLAY 0.659574 (7760 6860);
PAINT MONO (7760 6860);
DISPLAY INVISIBLE (7760 6860);
FORCEPROP 1 LAST HDL_POWER P3V3_9ZXL045_VDD
J 1
(7750 6950);
DISPLAY 0.872340 (7750 6950);
PAINT GREEN (7750 6950);
FORCEPROP 1 LAST PATH I29
J 0
(7800 6925);
DISPLAY 0.872340 (7800 6925);
PAINT AQUA (7800 6925);
DISPLAY INVISIBLE (7800 6925);
FORCEPROP 2 LAST CDS_LIB logical_power
J 0
(7750 6900);
DISPLAY INVISIBLE (7750 6900);
FORCEADD Q_RES..2
(7275 4100);
FORCEPROP 1 LAST PART_NUMBER CS24752FB03
J 0
(7315 3975);
DISPLAY 0.638298 (7315 3975);
DISPLAY INVISIBLE (7315 3975);
FORCEPROP 1 LAST PACK_TYPE 0402LF
J 0
(7315 3975);
DISPLAY 0.638298 (7315 3975);
FORCEPROP 1 LAST MATERIAL CHIP
J 0
(7315 4025);
DISPLAY 0.638298 (7315 4025);
FORCEPROP 1 LAST WATTAGE 1/16W
J 0
(7315 4075);
DISPLAY 0.638298 (7315 4075);
FORCEPROP 1 LAST TOLERANCE 1%
J 0
(7320 4125);
DISPLAY 0.638298 (7320 4125);
FORCEPROP 1 LAST VALUE 4.75K
J 0
(7320 4175);
DISPLAY 0.638298 (7320 4175);
FORCEPROP 1 LAST $LOCATION R4489
J 0
(7320 4225);
DISPLAY 0.978723 (7320 4225);
FORCEPROP 1 LASTPIN (7275 4200) $PN 1
J 0
(7280 4162);
DISPLAY 0.787234 (7280 4162);
PAINT MONO (7280 4162);
FORCEPROP 1 LASTPIN (7275 4000) $PN 2
J 0
(7280 4010);
DISPLAY 0.787234 (7280 4010);
PAINT MONO (7280 4010);
FORCEPROP 1 LAST PATH I30
J 0
(7325 4275);
DISPLAY 0.978723 (7325 4275);
PAINT WHITE (7325 4275);
DISPLAY INVISIBLE (7325 4275);
FORCEPROP 2 LAST CDS_LIB pure_quanta
J 0
(7275 4100);
DISPLAY INVISIBLE (7275 4100);
FORCEPROP 0 LAST CDS_LOCATION R4489
J 0
(7325 4275);
DISPLAY 1.021277 (7325 4275);
DISPLAY INVISIBLE (7325 4275);
FORCEPROP 0 LAST $SEC 1
J 0
(7325 4275);
DISPLAY 0.680851 (7325 4275);
PAINT MONO (7325 4275);
DISPLAY INVISIBLE (7325 4275);
FORCEPROP 0 LAST CDS_SEC 1
J 0
(7325 4275);
DISPLAY 1.021277 (7325 4275);
DISPLAY INVISIBLE (7325 4275);
FORCEADD Q_RES..2
(7275 3675);
FORCEPROP 1 LAST PART_NUMBER CS24752FB03
J 0
(7315 3550);
DISPLAY 0.638298 (7315 3550);
DISPLAY INVISIBLE (7315 3550);
FORCEPROP 1 LAST WATTAGE 1/16W
J 0
(7315 3650);
DISPLAY 0.638298 (7315 3650);
FORCEPROP 1 LAST TOLERANCE 1%
J 0
(7320 3700);
DISPLAY 0.638298 (7320 3700);
FORCEPROP 1 LAST VALUE 4.75K
J 0
(7320 3750);
DISPLAY 0.638298 (7320 3750);
FORCEPROP 1 LAST PACK_TYPE 0402LF
J 0
(7315 3550);
DISPLAY 0.638298 (7315 3550);
FORCEPROP 1 LAST MATERIAL EMPTY
J 0
(7315 3600);
DISPLAY 0.638298 (7315 3600);
PAINT RED (7315 3600);
FORCEPROP 1 LAST $LOCATION R4490
J 0
(7320 3800);
DISPLAY 0.978723 (7320 3800);
FORCEPROP 1 LASTPIN (7275 3775) $PN 1
J 0
(7280 3737);
DISPLAY 0.787234 (7280 3737);
PAINT MONO (7280 3737);
FORCEPROP 1 LASTPIN (7275 3575) $PN 2
J 0
(7280 3585);
DISPLAY 0.787234 (7280 3585);
PAINT MONO (7280 3585);
FORCEPROP 1 LAST PATH I31
J 0
(7325 3850);
DISPLAY 0.978723 (7325 3850);
PAINT WHITE (7325 3850);
DISPLAY INVISIBLE (7325 3850);
FORCEPROP 2 LAST CDS_LIB pure_quanta
J 0
(7275 3675);
DISPLAY INVISIBLE (7275 3675);
FORCEPROP 0 LAST CDS_LOCATION R4490
J 0
(7325 3850);
DISPLAY 1.021277 (7325 3850);
DISPLAY INVISIBLE (7325 3850);
FORCEPROP 0 LAST $SEC 1
J 0
(7325 3850);
DISPLAY 0.680851 (7325 3850);
PAINT MONO (7325 3850);
DISPLAY INVISIBLE (7325 3850);
FORCEPROP 0 LAST CDS_SEC 1
J 0
(7325 3850);
DISPLAY 1.021277 (7325 3850);
DISPLAY INVISIBLE (7325 3850);
FORCEADD UNIVERSAL_POWER..1
(7275 4450);
FORCEPROP 3 LASTPIN (7275 4400) SIG_NAME P3V3\g
J 0
(7285 4410);
DISPLAY 0.659574 (7285 4410);
PAINT MONO (7285 4410);
DISPLAY INVISIBLE (7285 4410);
FORCEPROP 1 LAST HDL_POWER P3V3
J 1
(7275 4500);
DISPLAY 0.872340 (7275 4500);
PAINT GREEN (7275 4500);
FORCEPROP 2 LAST CDS_LIB logical_power
J 0
(7275 4450);
DISPLAY INVISIBLE (7275 4450);
FORCEPROP 1 LAST PATH I32
J 0
(7325 4475);
DISPLAY 0.872340 (7325 4475);
PAINT AQUA (7325 4475);
DISPLAY INVISIBLE (7325 4475);
FORCEADD UNIVERSAL_GND..1
(7275 3425);
FORCEPROP 3 LASTPIN (7275 3475) SIG_NAME GND\g
J 0
(7285 3485);
DISPLAY 0.659574 (7285 3485);
PAINT MONO (7285 3485);
DISPLAY INVISIBLE (7285 3485);
FORCEPROP 2 LAST CDS_LIB logical_power
J 0
(7275 3425);
DISPLAY INVISIBLE (7275 3425);
FORCEPROP 1 LAST PATH I33
J 0
(7350 3425);
DISPLAY 0.872340 (7350 3425);
PAINT AQUA (7350 3425);
DISPLAY INVISIBLE (7350 3425);
FORCEPROP 1 LAST HDL_POWER GND
J 1
(7300 3350);
DISPLAY 0.872340 (7300 3350);
PAINT GREEN (7300 3350);
DISPLAY INVISIBLE (7300 3350);
FORCEADD OFFPAGE..2
(8000 3875);
FORCEPROP 2 LAST $XR0 211 
J 0
(8189 3875);
DISPLAY 0.638298 (8189 3875);
PAINT MONO (8189 3875);
FORCEPROP 2 LAST CDS_LIB standard
J 0
(8000 3875);
DISPLAY INVISIBLE (8000 3875);
FORCEPROP 2 LAST PATH I34
J 0
(8175 3950);
DISPLAY 1.021277 (8175 3950);
DISPLAY INVISIBLE (8175 3950);
FORCEPROP 1 LAST COMMENT_BODY TRUE
J 0
(7955 3780);
DISPLAY 0.872340 (7955 3780);
PAINT GREEN (7955 3780);
DISPLAY INVISIBLE (7955 3780);
FORCEPROP 1 LAST OFFPAGE TRUE
J 0
(8325 3750);
DISPLAY 0.872340 (8325 3750);
DISPLAY INVISIBLE (8325 3750);
FORCEADD OFFPAGE..1
(7000 6025);
FORCEPROP 2 LAST $XR0 211 
J 0
(6748 6025);
DISPLAY 0.638298 (6748 6025);
PAINT MONO (6748 6025);
FORCEPROP 2 LAST CDS_LIB standard
J 2
(7000 6025);
DISPLAY INVISIBLE (7000 6025);
FORCEPROP 2 LAST PATH I35
J 2
(6825 6100);
DISPLAY 1.021277 (6825 6100);
DISPLAY INVISIBLE (6825 6100);
FORCEPROP 1 LAST OFFPAGE TRUE
J 0
(7325 5900);
DISPLAY 1.170213 (7325 5900);
PAINT GREEN (7325 5900);
DISPLAY INVISIBLE (7325 5900);
FORCEPROP 1 LAST COMMENT_BODY TRUE
J 0
(7125 5925);
DISPLAY 1.170213 (7125 5925);
PAINT GREEN (7125 5925);
DISPLAY INVISIBLE (7125 5925);
FORCEADD OFFPAGE..1
(7000 5925);
FORCEPROP 2 LAST $XR0 237 
J 0
(6748 5925);
DISPLAY 0.638298 (6748 5925);
PAINT MONO (6748 5925);
FORCEPROP 2 LAST CDS_LIB standard
J 0
(7000 5925);
DISPLAY INVISIBLE (7000 5925);
FORCEPROP 2 LAST PATH I36
J 0
(7050 6000);
DISPLAY 1.021277 (7050 6000);
DISPLAY INVISIBLE (7050 6000);
FORCEPROP 1 LAST OFFPAGE TRUE
J 0
(7325 5800);
DISPLAY 1.170213 (7325 5800);
PAINT GREEN (7325 5800);
DISPLAY INVISIBLE (7325 5800);
FORCEPROP 1 LAST COMMENT_BODY TRUE
J 0
(7125 5825);
DISPLAY 1.170213 (7125 5825);
PAINT GREEN (7125 5825);
DISPLAY INVISIBLE (7125 5825);
FORCEADD OFFPAGE..1
(7000 5875);
FORCEPROP 2 LAST $XR0 237 
J 0
(6748 5875);
DISPLAY 0.638298 (6748 5875);
PAINT MONO (6748 5875);
FORCEPROP 2 LAST CDS_LIB standard
J 0
(7000 5875);
DISPLAY INVISIBLE (7000 5875);
FORCEPROP 2 LAST PATH I37
J 0
(7050 5950);
DISPLAY 1.021277 (7050 5950);
DISPLAY INVISIBLE (7050 5950);
FORCEPROP 1 LAST COMMENT_BODY TRUE
J 0
(7125 5775);
DISPLAY 1.170213 (7125 5775);
PAINT GREEN (7125 5775);
DISPLAY INVISIBLE (7125 5775);
FORCEPROP 1 LAST OFFPAGE TRUE
J 0
(7325 5750);
DISPLAY 1.170213 (7325 5750);
PAINT GREEN (7325 5750);
DISPLAY INVISIBLE (7325 5750);
FORCEADD OFFPAGE..1
(5550 5775);
FORCEPROP 2 LAST $XR2 206 
J 0
(5058 5775);
DISPLAY 0.638298 (5058 5775);
PAINT MONO (5058 5775);
FORCEPROP 2 LAST $XR1 223 
J 0
(5178 5775);
DISPLAY 0.638298 (5178 5775);
PAINT MONO (5178 5775);
FORCEPROP 2 LAST $XR0 208 
J 0
(5298 5775);
DISPLAY 0.638298 (5298 5775);
PAINT MONO (5298 5775);
FORCEPROP 2 LAST CDS_LIB standard
J 0
(5550 5775);
PAINT MONO (5550 5775);
DISPLAY INVISIBLE (5550 5775);
FORCEPROP 1 LAST OFFPAGE TRUE
J 0
(5875 5650);
DISPLAY 0.872340 (5875 5650);
PAINT GREEN (5875 5650);
DISPLAY INVISIBLE (5875 5650);
FORCEPROP 1 LAST COMMENT_BODY TRUE
J 0
(5675 5675);
DISPLAY 0.872340 (5675 5675);
PAINT GREEN (5675 5675);
DISPLAY INVISIBLE (5675 5675);
FORCEPROP 2 LAST PATH I38
J 0
(5275 5825);
DISPLAY 1.021277 (5275 5825);
DISPLAY INVISIBLE (5275 5825);
FORCEADD Q_RES..1
(6525 5775);
FORCEPROP 1 LAST PART_NUMBER CS04992FB07
J 0
(6400 5850);
DISPLAY 0.510638 (6400 5850);
DISPLAY INVISIBLE (6400 5850);
FORCEPROP 1 LAST PACK_TYPE 0402LF
J 0
(6400 5900);
DISPLAY 0.510638 (6400 5900);
FORCEPROP 1 LAST MATERIAL CHIP
J 0
(6850 5775);
DISPLAY 0.510638 (6850 5775);
FORCEPROP 1 LAST WATTAGE 1/16W
J 2
(6700 5900);
DISPLAY 0.510638 (6700 5900);
FORCEPROP 1 LAST VALUE 49.9
J 2
(6725 5775);
DISPLAY 0.510638 (6725 5775);
FORCEPROP 1 LAST TOLERANCE 1%
J 0
(6775 5775);
DISPLAY 0.510638 (6775 5775);
FORCEPROP 1 LAST $LOCATION R4476
J 0
(6300 5775);
DISPLAY 0.510638 (6300 5775);
FORCEPROP 1 LASTPIN (6425 5775) $PN 1
J 0
(6437 5787);
DISPLAY 0.787234 (6437 5787);
FORCEPROP 1 LASTPIN (6625 5775) $PN 2
J 0
(6587 5787);
DISPLAY 0.787234 (6587 5787);
FORCEPROP 2 LAST CDS_LIB pure_quanta
J 0
(6525 5775);
PAINT MONO (6525 5775);
DISPLAY INVISIBLE (6525 5775);
FORCEPROP 1 LAST PATH I39
J 0
(6475 5925);
DISPLAY 0.978723 (6475 5925);
PAINT WHITE (6475 5925);
DISPLAY INVISIBLE (6475 5925);
FORCEPROP 2 LAST CDS_LOCATION R4476
J 0
(6475 5975);
DISPLAY 1.021277 (6475 5975);
DISPLAY INVISIBLE (6475 5975);
FORCEPROP 2 LAST $SEC 1
J 0
(6475 5975);
DISPLAY 0.680851 (6475 5975);
PAINT MONO (6475 5975);
DISPLAY INVISIBLE (6475 5975);
FORCEPROP 2 LAST CDS_SEC 1
J 0
(6475 5975);
DISPLAY 1.021277 (6475 5975);
DISPLAY INVISIBLE (6475 5975);
FORCEADD Q_RES..1
(5600 8350);
FORCEPROP 1 LAST PART_NUMBER CS-1003F900
J 0
(5450 8425);
DISPLAY 0.510638 (5450 8425);
DISPLAY INVISIBLE (5450 8425);
FORCEPROP 1 LAST VALUE 1
J 2
(5800 8350);
DISPLAY 0.638298 (5800 8350);
FORCEPROP 1 LAST TOLERANCE 1%
J 0
(5825 8350);
DISPLAY 0.638298 (5825 8350);
FORCEPROP 1 LAST MATERIAL CHIP
J 0
(5925 8350);
DISPLAY 0.638298 (5925 8350);
FORCEPROP 1 LAST WATTAGE 1/10W
J 2
(5775 8475);
DISPLAY 0.510638 (5775 8475);
FORCEPROP 1 LAST PACK_TYPE 0603LF
J 0
(5450 8475);
DISPLAY 0.510638 (5450 8475);
FORCEPROP 1 LAST $LOCATION R4493
J 0
(5400 8350);
DISPLAY 0.638298 (5400 8350);
FORCEPROP 1 LASTPIN (5500 8350) $PN 1
J 0
(5512 8362);
DISPLAY 0.787234 (5512 8362);
PAINT MONO (5512 8362);
FORCEPROP 1 LASTPIN (5700 8350) $PN 2
J 0
(5662 8362);
DISPLAY 0.787234 (5662 8362);
PAINT MONO (5662 8362);
FORCEPROP 2 LAST CDS_LIB pure_quanta
J 0
(5600 8350);
DISPLAY INVISIBLE (5600 8350);
FORCEPROP 1 LAST PATH I4
J 0
(5550 8500);
DISPLAY 0.978723 (5550 8500);
PAINT WHITE (5550 8500);
DISPLAY INVISIBLE (5550 8500);
FORCEPROP 0 LAST CDS_LOCATION R4493
J 0
(5775 8500);
DISPLAY 1.021277 (5775 8500);
DISPLAY INVISIBLE (5775 8500);
FORCEPROP 0 LAST $SEC 1
J 0
(5775 8500);
DISPLAY 0.680851 (5775 8500);
PAINT MONO (5775 8500);
DISPLAY INVISIBLE (5775 8500);
FORCEPROP 0 LAST CDS_SEC 1
J 0
(5775 8500);
DISPLAY 1.021277 (5775 8500);
DISPLAY INVISIBLE (5775 8500);
FORCEADD OFFPAGE..2
(10675 6075);
FORCEPROP 2 LAST $XR0 207 
J 0
(10864 6075);
DISPLAY 0.638298 (10864 6075);
PAINT MONO (10864 6075);
FORCEPROP 2 LAST CDS_LIB standard
J 0
(10675 6075);
DISPLAY INVISIBLE (10675 6075);
FORCEPROP 1 LAST COMMENT_BODY TRUE
J 0
(10630 5980);
DISPLAY 0.872340 (10630 5980);
PAINT GREEN (10630 5980);
DISPLAY INVISIBLE (10630 5980);
FORCEPROP 1 LAST OFFPAGE TRUE
J 0
(11000 5950);
DISPLAY 0.872340 (11000 5950);
PAINT GREEN (11000 5950);
DISPLAY INVISIBLE (11000 5950);
FORCEPROP 2 LAST PATH I40
J 0
(10875 6125);
DISPLAY 1.021277 (10875 6125);
DISPLAY INVISIBLE (10875 6125);
FORCEADD OFFPAGE..2
(10675 6025);
FORCEPROP 2 LAST $XR0 207 
J 0
(10864 6025);
DISPLAY 0.638298 (10864 6025);
PAINT MONO (10864 6025);
FORCEPROP 2 LAST CDS_LIB standard
J 0
(10675 6025);
DISPLAY INVISIBLE (10675 6025);
FORCEPROP 1 LAST COMMENT_BODY TRUE
J 0
(10630 5930);
DISPLAY 0.872340 (10630 5930);
PAINT GREEN (10630 5930);
DISPLAY INVISIBLE (10630 5930);
FORCEPROP 1 LAST OFFPAGE TRUE
J 0
(11000 5900);
DISPLAY 0.872340 (11000 5900);
PAINT GREEN (11000 5900);
DISPLAY INVISIBLE (11000 5900);
FORCEPROP 2 LAST PATH I41
J 0
(10875 6075);
DISPLAY 1.021277 (10875 6075);
DISPLAY INVISIBLE (10875 6075);
FORCEADD OFFPAGE..2
(10675 6175);
FORCEPROP 2 LAST $XR0 207 
J 0
(10864 6175);
DISPLAY 0.638298 (10864 6175);
PAINT MONO (10864 6175);
FORCEPROP 2 LAST CDS_LIB standard
J 0
(10675 6175);
DISPLAY INVISIBLE (10675 6175);
FORCEPROP 1 LAST OFFPAGE TRUE
J 0
(11000 6050);
DISPLAY 0.872340 (11000 6050);
PAINT GREEN (11000 6050);
DISPLAY INVISIBLE (11000 6050);
FORCEPROP 1 LAST COMMENT_BODY TRUE
J 0
(10630 6080);
DISPLAY 0.872340 (10630 6080);
PAINT GREEN (10630 6080);
DISPLAY INVISIBLE (10630 6080);
FORCEPROP 2 LAST PATH I42
J 0
(10875 6225);
DISPLAY 1.021277 (10875 6225);
DISPLAY INVISIBLE (10875 6225);
FORCEADD OFFPAGE..2
(10675 6125);
FORCEPROP 2 LAST $XR0 207 
J 0
(10864 6125);
DISPLAY 0.638298 (10864 6125);
PAINT MONO (10864 6125);
FORCEPROP 2 LAST CDS_LIB standard
J 0
(10675 6125);
DISPLAY INVISIBLE (10675 6125);
FORCEPROP 1 LAST OFFPAGE TRUE
J 0
(11000 6000);
DISPLAY 0.872340 (11000 6000);
PAINT GREEN (11000 6000);
DISPLAY INVISIBLE (11000 6000);
FORCEPROP 1 LAST COMMENT_BODY TRUE
J 0
(10630 6030);
DISPLAY 0.872340 (10630 6030);
PAINT GREEN (10630 6030);
DISPLAY INVISIBLE (10630 6030);
FORCEPROP 2 LAST PATH I43
J 0
(10875 6175);
DISPLAY 1.021277 (10875 6175);
DISPLAY INVISIBLE (10875 6175);
FORCEADD OFFPAGE..2
(10675 6275);
FORCEPROP 2 LAST $XR0 207 
J 0
(10864 6275);
DISPLAY 0.638298 (10864 6275);
PAINT MONO (10864 6275);
FORCEPROP 1 LAST COMMENT_BODY TRUE
J 0
(10630 6180);
DISPLAY 0.872340 (10630 6180);
PAINT GREEN (10630 6180);
DISPLAY INVISIBLE (10630 6180);
FORCEPROP 1 LAST OFFPAGE TRUE
J 0
(11000 6150);
DISPLAY 0.872340 (11000 6150);
PAINT GREEN (11000 6150);
DISPLAY INVISIBLE (11000 6150);
FORCEPROP 2 LAST CDS_LIB standard
J 0
(10675 6275);
DISPLAY INVISIBLE (10675 6275);
FORCEPROP 2 LAST PATH I44
J 0
(10875 6325);
DISPLAY 1.021277 (10875 6325);
DISPLAY INVISIBLE (10875 6325);
FORCEADD OFFPAGE..2
(10675 6225);
FORCEPROP 2 LAST $XR0 207 
J 0
(10864 6225);
DISPLAY 0.638298 (10864 6225);
PAINT MONO (10864 6225);
FORCEPROP 1 LAST COMMENT_BODY TRUE
J 0
(10630 6130);
DISPLAY 0.872340 (10630 6130);
PAINT GREEN (10630 6130);
DISPLAY INVISIBLE (10630 6130);
FORCEPROP 1 LAST OFFPAGE TRUE
J 0
(11000 6100);
DISPLAY 0.872340 (11000 6100);
PAINT GREEN (11000 6100);
DISPLAY INVISIBLE (11000 6100);
FORCEPROP 2 LAST CDS_LIB standard
J 0
(10675 6225);
DISPLAY INVISIBLE (10675 6225);
FORCEPROP 2 LAST PATH I45
J 0
(10875 6275);
DISPLAY 1.021277 (10875 6275);
DISPLAY INVISIBLE (10875 6275);
FORCEADD Q_RES..2
(9275 4100);
FORCEPROP 1 LAST PART_NUMBER CS31002FB08
J 0
(9315 3975);
DISPLAY 0.638298 (9315 3975);
DISPLAY INVISIBLE (9315 3975);
FORCEPROP 1 LAST VALUE 10K
J 0
(9320 4175);
DISPLAY 0.638298 (9320 4175);
FORCEPROP 1 LAST PACK_TYPE 0402LF
J 0
(9315 3975);
DISPLAY 0.638298 (9315 3975);
FORCEPROP 1 LAST MATERIAL CHIP
J 0
(9300 4025);
DISPLAY 0.638298 (9300 4025);
FORCEPROP 1 LAST WATTAGE 1/16W
J 0
(9315 4075);
DISPLAY 0.638298 (9315 4075);
FORCEPROP 1 LAST TOLERANCE 1%
J 0
(9320 4125);
DISPLAY 0.638298 (9320 4125);
FORCEPROP 1 LAST $LOCATION R4491
J 0
(9320 4225);
DISPLAY 0.978723 (9320 4225);
FORCEPROP 1 LASTPIN (9275 4200) $PN 1
J 0
(9280 4162);
DISPLAY 0.787234 (9280 4162);
PAINT MONO (9280 4162);
FORCEPROP 1 LASTPIN (9275 4000) $PN 2
J 0
(9280 4010);
DISPLAY 0.787234 (9280 4010);
PAINT MONO (9280 4010);
FORCEPROP 2 LAST CDS_LIB pure_quanta
J 0
(9275 4100);
DISPLAY INVISIBLE (9275 4100);
FORCEPROP 1 LAST PATH I48
J 0
(9325 4275);
DISPLAY 0.978723 (9325 4275);
PAINT WHITE (9325 4275);
DISPLAY INVISIBLE (9325 4275);
FORCEPROP 0 LAST CDS_LOCATION R4491
J 0
(9325 4275);
DISPLAY 1.021277 (9325 4275);
DISPLAY INVISIBLE (9325 4275);
FORCEPROP 0 LAST $SEC 1
J 0
(9325 4275);
DISPLAY 0.680851 (9325 4275);
PAINT MONO (9325 4275);
DISPLAY INVISIBLE (9325 4275);
FORCEPROP 0 LAST CDS_SEC 1
J 0
(9325 4275);
DISPLAY 1.021277 (9325 4275);
DISPLAY INVISIBLE (9325 4275);
FORCEADD Q_RES..2
(9275 3625);
FORCEPROP 1 LAST PART_NUMBER CS31002FB08
J 0
(9315 3500);
DISPLAY 0.638298 (9315 3500);
DISPLAY INVISIBLE (9315 3500);
FORCEPROP 1 LAST PACK_TYPE 0402LF
J 0
(9315 3500);
DISPLAY 0.638298 (9315 3500);
FORCEPROP 1 LAST VALUE 10K
J 0
(9320 3700);
DISPLAY 0.638298 (9320 3700);
FORCEPROP 1 LAST TOLERANCE 1%
J 0
(9320 3650);
DISPLAY 0.638298 (9320 3650);
FORCEPROP 1 LAST WATTAGE 1/16W
J 0
(9315 3600);
DISPLAY 0.638298 (9315 3600);
FORCEPROP 1 LAST MATERIAL CHIP
J 0
(9300 3550);
DISPLAY 0.638298 (9300 3550);
FORCEPROP 1 LAST $LOCATION R4492
J 0
(9320 3750);
DISPLAY 0.978723 (9320 3750);
FORCEPROP 1 LASTPIN (9275 3725) $PN 1
J 0
(9280 3687);
DISPLAY 0.787234 (9280 3687);
PAINT MONO (9280 3687);
FORCEPROP 1 LASTPIN (9275 3525) $PN 2
J 0
(9280 3535);
DISPLAY 0.787234 (9280 3535);
PAINT MONO (9280 3535);
FORCEPROP 2 LAST CDS_LIB pure_quanta
J 0
(9275 3625);
DISPLAY INVISIBLE (9275 3625);
FORCEPROP 1 LAST PATH I49
J 0
(9325 3800);
DISPLAY 0.978723 (9325 3800);
PAINT WHITE (9325 3800);
DISPLAY INVISIBLE (9325 3800);
FORCEPROP 0 LAST CDS_LOCATION R4492
J 0
(9325 3800);
DISPLAY 1.021277 (9325 3800);
DISPLAY INVISIBLE (9325 3800);
FORCEPROP 0 LAST $SEC 1
J 0
(9325 3800);
DISPLAY 0.680851 (9325 3800);
PAINT MONO (9325 3800);
DISPLAY INVISIBLE (9325 3800);
FORCEPROP 0 LAST CDS_SEC 1
J 0
(9325 3800);
DISPLAY 1.021277 (9325 3800);
DISPLAY INVISIBLE (9325 3800);
FORCEADD Q_CAP..1
(6025 8175);
FORCEPROP 1 LAST PART_NUMBER CH6101ME900
J 0
(6075 7975);
DISPLAY 0.510638 (6075 7975);
DISPLAY INVISIBLE (6075 7975);
FORCEPROP 1 LAST VOLTAGE 6.3V
J 0
(6075 8175);
DISPLAY 0.638298 (6075 8175);
FORCEPROP 1 LAST PACK_TYPE C0603
J 0
(6075 8025);
DISPLAY 0.638298 (6075 8025);
FORCEPROP 1 LAST MATERIAL X6S
J 0
(6075 8075);
DISPLAY 0.638298 (6075 8075);
FORCEPROP 1 LAST TOLERANCE 20%
J 0
(6075 8125);
DISPLAY 0.638298 (6075 8125);
FORCEPROP 1 LAST VALUE 10UF
J 0
(6075 8225);
DISPLAY 0.638298 (6075 8225);
FORCEPROP 1 LAST $LOCATION C2331
J 0
(6075 8275);
DISPLAY 0.978723 (6075 8275);
FORCEPROP 1 LASTPIN (6025 8275) $PN 1
J 0
(6035 8255);
DISPLAY 0.787234 (6035 8255);
PAINT MONO (6035 8255);
FORCEPROP 1 LASTPIN (6025 8075) $PN 2
J 0
(6035 8055);
DISPLAY 0.787234 (6035 8055);
PAINT MONO (6035 8055);
FORCEPROP 1 LAST PATH I5
J 0
(6075 8325);
DISPLAY 0.978723 (6075 8325);
PAINT WHITE (6075 8325);
DISPLAY INVISIBLE (6075 8325);
FORCEPROP 2 LAST CDS_LIB pure_quanta
J 0
(6025 8175);
DISPLAY INVISIBLE (6025 8175);
FORCEPROP 0 LAST CDS_LOCATION C2331
J 0
(6075 8325);
DISPLAY 1.021277 (6075 8325);
DISPLAY INVISIBLE (6075 8325);
FORCEPROP 0 LAST $SEC 1
J 0
(6075 8325);
DISPLAY 0.680851 (6075 8325);
PAINT MONO (6075 8325);
DISPLAY INVISIBLE (6075 8325);
FORCEPROP 0 LAST CDS_SEC 1
J 0
(6075 8325);
DISPLAY 1.021277 (6075 8325);
DISPLAY INVISIBLE (6075 8325);
FORCEADD UNIVERSAL_POWER..1
(9275 4400);
FORCEPROP 3 LASTPIN (9275 4350) SIG_NAME P3V3\g
J 0
(9285 4360);
DISPLAY 0.659574 (9285 4360);
PAINT MONO (9285 4360);
DISPLAY INVISIBLE (9285 4360);
FORCEPROP 1 LAST HDL_POWER P3V3
J 1
(9275 4450);
DISPLAY 0.872340 (9275 4450);
PAINT GREEN (9275 4450);
FORCEPROP 2 LAST CDS_LIB logical_power
J 0
(9275 4400);
DISPLAY INVISIBLE (9275 4400);
FORCEPROP 1 LAST PATH I50
J 0
(9325 4425);
DISPLAY 0.872340 (9325 4425);
PAINT AQUA (9325 4425);
DISPLAY INVISIBLE (9325 4425);
FORCEADD UNIVERSAL_GND..1
(9275 3375);
FORCEPROP 3 LASTPIN (9275 3425) SIG_NAME GND\g
J 0
(9285 3435);
DISPLAY 0.659574 (9285 3435);
PAINT MONO (9285 3435);
DISPLAY INVISIBLE (9285 3435);
FORCEPROP 2 LAST CDS_LIB logical_power
J 0
(9275 3375);
DISPLAY INVISIBLE (9275 3375);
FORCEPROP 1 LAST PATH I51
J 0
(9350 3375);
DISPLAY 0.872340 (9350 3375);
PAINT AQUA (9350 3375);
DISPLAY INVISIBLE (9350 3375);
FORCEPROP 1 LAST HDL_POWER GND
J 1
(9300 3300);
DISPLAY 0.872340 (9300 3300);
PAINT GREEN (9300 3300);
DISPLAY INVISIBLE (9300 3300);
FORCEADD OFFPAGE..2
(10000 3875);
FORCEPROP 2 LAST $XR0 211 
J 0
(10189 3875);
DISPLAY 0.638298 (10189 3875);
PAINT MONO (10189 3875);
FORCEPROP 1 LAST COMMENT_BODY TRUE
J 0
(9955 3780);
DISPLAY 0.872340 (9955 3780);
PAINT GREEN (9955 3780);
DISPLAY INVISIBLE (9955 3780);
FORCEPROP 1 LAST OFFPAGE TRUE
J 0
(10325 3750);
DISPLAY 0.872340 (10325 3750);
DISPLAY INVISIBLE (10325 3750);
FORCEPROP 2 LAST PATH I52
J 0
(10175 3950);
DISPLAY 1.021277 (10175 3950);
DISPLAY INVISIBLE (10175 3950);
FORCEPROP 2 LAST CDS_LIB standard
J 0
(10000 3875);
DISPLAY INVISIBLE (10000 3875);
FORCEADD OFFPAGE..1
R 2
(10025 6475);
FORCEPROP 2 LAST $XR0 211 
J 0
(10211 6475);
DISPLAY 0.638298 (10211 6475);
PAINT MONO (10211 6475);
FORCEPROP 1 LAST OFFPAGE TRUE
J 2
(9700 6350);
DISPLAY 1.170213 (9700 6350);
PAINT GREEN (9700 6350);
DISPLAY INVISIBLE (9700 6350);
FORCEPROP 1 LAST COMMENT_BODY TRUE
J 2
(9900 6375);
DISPLAY 1.170213 (9900 6375);
PAINT GREEN (9900 6375);
DISPLAY INVISIBLE (9900 6375);
FORCEPROP 2 LAST PATH I53
J 2
(9975 6550);
DISPLAY 1.021277 (9975 6550);
DISPLAY INVISIBLE (9975 6550);
FORCEPROP 2 LAST CDS_LIB standard
J 2
(10025 6475);
DISPLAY INVISIBLE (10025 6475);
FORCEADD Q_CAP..1
(8950 7825);
FORCEPROP 1 LAST PART_NUMBER CH4104K1B00
J 0
(9000 7675);
DISPLAY 0.404255 (9000 7675);
DISPLAY INVISIBLE (9000 7675);
FORCEPROP 1 LAST MATERIAL X7R
J 0
(9000 7725);
DISPLAY 0.510638 (9000 7725);
FORCEPROP 1 LAST VALUE 0.1UF
J 0
(9000 7875);
DISPLAY 0.510638 (9000 7875);
FORCEPROP 1 LAST PACK_TYPE 0402
J 0
(9000 7625);
DISPLAY 0.510638 (9000 7625);
FORCEPROP 1 LAST VOLTAGE 25V
J 0
(9000 7825);
DISPLAY 0.510638 (9000 7825);
FORCEPROP 1 LAST TOLERANCE 10%
J 0
(9000 7775);
DISPLAY 0.510638 (9000 7775);
FORCEPROP 1 LAST $LOCATION C2329
J 0
(9000 7925);
DISPLAY 0.978723 (9000 7925);
FORCEPROP 1 LASTPIN (8950 7925) $PN 1
J 0
(8960 7905);
DISPLAY 0.787234 (8960 7905);
PAINT MONO (8960 7905);
FORCEPROP 1 LASTPIN (8950 7725) $PN 2
J 0
(8960 7705);
DISPLAY 0.787234 (8960 7705);
PAINT MONO (8960 7705);
FORCEPROP 2 LAST CDS_LIB pure_quanta
J 0
(8950 7825);
DISPLAY INVISIBLE (8950 7825);
FORCEPROP 1 LAST PATH I54
J 0
(9000 7975);
DISPLAY 0.978723 (9000 7975);
PAINT WHITE (9000 7975);
DISPLAY INVISIBLE (9000 7975);
FORCEPROP 0 LAST CDS_LOCATION C2329
J 0
(9000 7975);
DISPLAY 1.021277 (9000 7975);
DISPLAY INVISIBLE (9000 7975);
FORCEPROP 0 LAST $SEC 1
J 0
(9000 7975);
DISPLAY 0.680851 (9000 7975);
PAINT MONO (9000 7975);
DISPLAY INVISIBLE (9000 7975);
FORCEPROP 0 LAST CDS_SEC 1
J 0
(9000 7975);
DISPLAY 1.021277 (9000 7975);
DISPLAY INVISIBLE (9000 7975);
FORCEADD Q_CAP..1
(9200 7825);
FORCEPROP 1 LAST PART_NUMBER CH4104K1B00
J 0
(9250 7675);
DISPLAY 0.404255 (9250 7675);
DISPLAY INVISIBLE (9250 7675);
FORCEPROP 1 LAST VALUE 0.1UF
J 0
(9250 7875);
DISPLAY 0.510638 (9250 7875);
FORCEPROP 1 LAST MATERIAL X7R
J 0
(9250 7725);
DISPLAY 0.510638 (9250 7725);
FORCEPROP 1 LAST TOLERANCE 10%
J 0
(9250 7775);
DISPLAY 0.510638 (9250 7775);
FORCEPROP 1 LAST PACK_TYPE 0402
J 0
(9250 7625);
DISPLAY 0.510638 (9250 7625);
FORCEPROP 1 LAST VOLTAGE 25V
J 0
(9250 7825);
DISPLAY 0.510638 (9250 7825);
FORCEPROP 1 LAST $LOCATION C2330
J 0
(9250 7925);
DISPLAY 0.978723 (9250 7925);
FORCEPROP 1 LASTPIN (9200 7925) $PN 1
J 0
(9210 7905);
DISPLAY 0.787234 (9210 7905);
PAINT MONO (9210 7905);
FORCEPROP 1 LASTPIN (9200 7725) $PN 2
J 0
(9210 7705);
DISPLAY 0.787234 (9210 7705);
PAINT MONO (9210 7705);
FORCEPROP 1 LAST PATH I55
J 0
(9250 7975);
DISPLAY 0.978723 (9250 7975);
PAINT WHITE (9250 7975);
DISPLAY INVISIBLE (9250 7975);
FORCEPROP 2 LAST CDS_LIB pure_quanta
J 0
(9200 7825);
DISPLAY INVISIBLE (9200 7825);
FORCEPROP 0 LAST CDS_LOCATION C2330
J 0
(9250 7975);
DISPLAY 1.021277 (9250 7975);
DISPLAY INVISIBLE (9250 7975);
FORCEPROP 0 LAST $SEC 1
J 0
(9250 7975);
DISPLAY 0.680851 (9250 7975);
PAINT MONO (9250 7975);
DISPLAY INVISIBLE (9250 7975);
FORCEPROP 0 LAST CDS_SEC 1
J 0
(9250 7975);
DISPLAY 1.021277 (9250 7975);
DISPLAY INVISIBLE (9250 7975);
FORCEADD Q_CAP..1
(9450 7825);
FORCEPROP 1 LAST PART_NUMBER CH4104K1B00
J 0
(9500 7675);
DISPLAY 0.404255 (9500 7675);
DISPLAY INVISIBLE (9500 7675);
FORCEPROP 1 LAST VOLTAGE 25V
J 0
(9500 7825);
DISPLAY 0.510638 (9500 7825);
FORCEPROP 1 LAST VALUE 0.1UF
J 0
(9500 7875);
DISPLAY 0.510638 (9500 7875);
FORCEPROP 1 LAST TOLERANCE 10%
J 0
(9500 7775);
DISPLAY 0.510638 (9500 7775);
FORCEPROP 1 LAST PACK_TYPE 0402
J 0
(9500 7625);
DISPLAY 0.510638 (9500 7625);
FORCEPROP 1 LAST MATERIAL X7R
J 0
(9500 7725);
DISPLAY 0.510638 (9500 7725);
FORCEPROP 1 LAST $LOCATION C2333
J 0
(9500 7925);
DISPLAY 0.978723 (9500 7925);
FORCEPROP 1 LASTPIN (9450 7925) $PN 1
J 0
(9460 7905);
DISPLAY 0.787234 (9460 7905);
PAINT MONO (9460 7905);
FORCEPROP 1 LASTPIN (9450 7725) $PN 2
J 0
(9460 7705);
DISPLAY 0.787234 (9460 7705);
PAINT MONO (9460 7705);
FORCEPROP 1 LAST PATH I56
J 0
(9500 7975);
DISPLAY 0.978723 (9500 7975);
PAINT WHITE (9500 7975);
DISPLAY INVISIBLE (9500 7975);
FORCEPROP 2 LAST CDS_LIB pure_quanta
J 0
(9450 7825);
DISPLAY INVISIBLE (9450 7825);
FORCEPROP 0 LAST CDS_LOCATION C2333
J 0
(9500 7975);
DISPLAY 1.021277 (9500 7975);
DISPLAY INVISIBLE (9500 7975);
FORCEPROP 0 LAST $SEC 1
J 0
(9500 7975);
DISPLAY 0.680851 (9500 7975);
PAINT MONO (9500 7975);
DISPLAY INVISIBLE (9500 7975);
FORCEPROP 0 LAST CDS_SEC 1
J 0
(9500 7975);
DISPLAY 1.021277 (9500 7975);
DISPLAY INVISIBLE (9500 7975);
FORCEADD Q_CAP..1
(9700 7825);
FORCEPROP 1 LAST PART_NUMBER CH4104K1B00
J 0
(9750 7675);
DISPLAY 0.404255 (9750 7675);
DISPLAY INVISIBLE (9750 7675);
FORCEPROP 1 LAST PACK_TYPE 0402
J 0
(9750 7625);
DISPLAY 0.510638 (9750 7625);
FORCEPROP 1 LAST VOLTAGE 25V
J 0
(9750 7825);
DISPLAY 0.510638 (9750 7825);
FORCEPROP 1 LAST TOLERANCE 10%
J 0
(9750 7775);
DISPLAY 0.510638 (9750 7775);
FORCEPROP 1 LAST VALUE 0.1UF
J 0
(9750 7875);
DISPLAY 0.510638 (9750 7875);
FORCEPROP 1 LAST MATERIAL X7R
J 0
(9750 7725);
DISPLAY 0.510638 (9750 7725);
FORCEPROP 1 LAST $LOCATION C2336
J 0
(9750 7925);
DISPLAY 0.978723 (9750 7925);
FORCEPROP 1 LASTPIN (9700 7925) $PN 1
J 0
(9710 7905);
DISPLAY 0.787234 (9710 7905);
PAINT MONO (9710 7905);
FORCEPROP 1 LASTPIN (9700 7725) $PN 2
J 0
(9710 7705);
DISPLAY 0.787234 (9710 7705);
PAINT MONO (9710 7705);
FORCEPROP 1 LAST PATH I57
J 0
(9750 7975);
DISPLAY 0.978723 (9750 7975);
PAINT WHITE (9750 7975);
DISPLAY INVISIBLE (9750 7975);
FORCEPROP 2 LAST CDS_LIB pure_quanta
J 0
(9700 7825);
DISPLAY INVISIBLE (9700 7825);
FORCEPROP 0 LAST CDS_LOCATION C2336
J 0
(9750 7975);
DISPLAY 1.021277 (9750 7975);
DISPLAY INVISIBLE (9750 7975);
FORCEPROP 0 LAST $SEC 1
J 0
(9750 7975);
DISPLAY 0.680851 (9750 7975);
PAINT MONO (9750 7975);
DISPLAY INVISIBLE (9750 7975);
FORCEPROP 0 LAST CDS_SEC 1
J 0
(9750 7975);
DISPLAY 1.021277 (9750 7975);
DISPLAY INVISIBLE (9750 7975);
FORCEADD Q_CAP..1
(6375 8175);
FORCEPROP 1 LAST PART_NUMBER CH4104K1B00
J 0
(6425 8025);
DISPLAY 0.404255 (6425 8025);
DISPLAY INVISIBLE (6425 8025);
FORCEPROP 1 LAST VALUE 0.1UF
J 0
(6425 8225);
DISPLAY 0.510638 (6425 8225);
FORCEPROP 1 LAST TOLERANCE 10%
J 0
(6425 8125);
DISPLAY 0.510638 (6425 8125);
FORCEPROP 1 LAST VOLTAGE 25V
J 0
(6425 8175);
DISPLAY 0.510638 (6425 8175);
FORCEPROP 1 LAST PACK_TYPE 0402
J 0
(6425 7975);
DISPLAY 0.510638 (6425 7975);
FORCEPROP 1 LAST MATERIAL X7R
J 0
(6425 8075);
DISPLAY 0.510638 (6425 8075);
FORCEPROP 1 LAST $LOCATION C2334
J 0
(6425 8275);
DISPLAY 0.978723 (6425 8275);
FORCEPROP 1 LASTPIN (6375 8275) $PN 1
J 0
(6385 8255);
DISPLAY 0.787234 (6385 8255);
PAINT MONO (6385 8255);
FORCEPROP 1 LASTPIN (6375 8075) $PN 2
J 0
(6385 8055);
DISPLAY 0.787234 (6385 8055);
PAINT MONO (6385 8055);
FORCEPROP 2 LAST CDS_LIB pure_quanta
J 0
(6375 8175);
DISPLAY INVISIBLE (6375 8175);
FORCEPROP 1 LAST PATH I58
J 0
(6425 8325);
DISPLAY 0.978723 (6425 8325);
PAINT WHITE (6425 8325);
DISPLAY INVISIBLE (6425 8325);
FORCEPROP 0 LAST CDS_LOCATION C2334
J 0
(6425 8325);
DISPLAY 1.021277 (6425 8325);
DISPLAY INVISIBLE (6425 8325);
FORCEPROP 0 LAST $SEC 1
J 0
(6425 8325);
DISPLAY 0.680851 (6425 8325);
PAINT MONO (6425 8325);
DISPLAY INVISIBLE (6425 8325);
FORCEPROP 0 LAST CDS_SEC 1
J 0
(6425 8325);
DISPLAY 1.021277 (6425 8325);
DISPLAY INVISIBLE (6425 8325);
FORCEADD Q_CAP..1
(6400 7375);
FORCEPROP 1 LAST PART_NUMBER CH4104K1B00
J 0
(6450 7225);
DISPLAY 0.404255 (6450 7225);
DISPLAY INVISIBLE (6450 7225);
FORCEPROP 1 LAST VOLTAGE 25V
J 0
(6450 7375);
DISPLAY 0.510638 (6450 7375);
FORCEPROP 1 LAST MATERIAL X7R
J 0
(6450 7275);
DISPLAY 0.510638 (6450 7275);
FORCEPROP 1 LAST VALUE 0.1UF
J 0
(6450 7425);
DISPLAY 0.510638 (6450 7425);
FORCEPROP 1 LAST PACK_TYPE 0402
J 0
(6450 7175);
DISPLAY 0.510638 (6450 7175);
FORCEPROP 1 LAST TOLERANCE 10%
J 0
(6450 7325);
DISPLAY 0.510638 (6450 7325);
FORCEPROP 1 LAST $LOCATION C2335
J 0
(6450 7475);
DISPLAY 0.978723 (6450 7475);
FORCEPROP 1 LASTPIN (6400 7475) $PN 1
J 0
(6410 7455);
DISPLAY 0.787234 (6410 7455);
PAINT MONO (6410 7455);
FORCEPROP 1 LASTPIN (6400 7275) $PN 2
J 0
(6410 7255);
DISPLAY 0.787234 (6410 7255);
PAINT MONO (6410 7255);
FORCEPROP 2 LAST CDS_LIB pure_quanta
J 0
(6400 7375);
DISPLAY INVISIBLE (6400 7375);
FORCEPROP 1 LAST PATH I59
J 0
(6450 7525);
DISPLAY 0.978723 (6450 7525);
PAINT WHITE (6450 7525);
DISPLAY INVISIBLE (6450 7525);
FORCEPROP 0 LAST CDS_LOCATION C2335
J 0
(6450 7525);
DISPLAY 1.021277 (6450 7525);
DISPLAY INVISIBLE (6450 7525);
FORCEPROP 0 LAST $SEC 1
J 0
(6450 7525);
DISPLAY 0.680851 (6450 7525);
PAINT MONO (6450 7525);
DISPLAY INVISIBLE (6450 7525);
FORCEPROP 0 LAST CDS_SEC 1
J 0
(6450 7525);
DISPLAY 1.021277 (6450 7525);
DISPLAY INVISIBLE (6450 7525);
FORCEADD OFFPAGE..1
(7000 6175);
FORCEPROP 2 LAST $XR0 206 
J 0
(6748 6175);
DISPLAY 0.638298 (6748 6175);
PAINT MONO (6748 6175);
FORCEPROP 1 LAST OFFPAGE TRUE
J 0
(7325 6050);
DISPLAY 1.170213 (7325 6050);
PAINT GREEN (7325 6050);
DISPLAY INVISIBLE (7325 6050);
FORCEPROP 1 LAST COMMENT_BODY TRUE
J 0
(7125 6075);
DISPLAY 1.170213 (7125 6075);
PAINT GREEN (7125 6075);
DISPLAY INVISIBLE (7125 6075);
FORCEPROP 2 LAST PATH I62
J 0
(7050 6250);
DISPLAY 1.021277 (7050 6250);
DISPLAY INVISIBLE (7050 6250);
FORCEPROP 2 LAST CDS_LIB standard
J 0
(7000 6175);
DISPLAY INVISIBLE (7000 6175);
FORCEADD OFFPAGE..1
(7000 6125);
FORCEPROP 2 LAST $XR0 206 
J 0
(6748 6125);
DISPLAY 0.638298 (6748 6125);
PAINT MONO (6748 6125);
FORCEPROP 1 LAST COMMENT_BODY TRUE
J 0
(7125 6025);
DISPLAY 1.170213 (7125 6025);
PAINT GREEN (7125 6025);
DISPLAY INVISIBLE (7125 6025);
FORCEPROP 1 LAST OFFPAGE TRUE
J 0
(7325 6000);
DISPLAY 1.170213 (7325 6000);
PAINT GREEN (7325 6000);
DISPLAY INVISIBLE (7325 6000);
FORCEPROP 2 LAST PATH I63
J 0
(7050 6200);
DISPLAY 1.021277 (7050 6200);
DISPLAY INVISIBLE (7050 6200);
FORCEPROP 2 LAST CDS_LIB standard
J 0
(7000 6125);
DISPLAY INVISIBLE (7000 6125);
FORCEADD OFFPAGE..1
R 2
(12150 5725);
FORCEPROP 2 LAST $XR0 215 
J 0
(12336 5725);
DISPLAY 0.638298 (12336 5725);
PAINT MONO (12336 5725);
FORCEPROP 1 LAST OFFPAGE TRUE
J 2
(11825 5600);
DISPLAY 1.170213 (11825 5600);
PAINT GREEN (11825 5600);
DISPLAY INVISIBLE (11825 5600);
FORCEPROP 1 LAST COMMENT_BODY TRUE
J 2
(12025 5625);
DISPLAY 1.170213 (12025 5625);
PAINT GREEN (12025 5625);
DISPLAY INVISIBLE (12025 5625);
FORCEPROP 2 LAST PATH I66
J 0
(12325 5800);
DISPLAY 1.021277 (12325 5800);
DISPLAY INVISIBLE (12325 5800);
FORCEPROP 2 LAST CDS_LIB standard
J 0
(12150 5725);
DISPLAY INVISIBLE (12150 5725);
FORCEADD Q_RES..1
(10250 5575);
FORCEPROP 1 LAST PART_NUMBER CS31002FB08
J 0
(10200 5675);
DISPLAY 0.978723 (10200 5675);
DISPLAY INVISIBLE (10200 5675);
FORCEPROP 1 LAST MATERIAL CHIP
J 0
(10600 5575);
DISPLAY 0.638298 (10600 5575);
FORCEPROP 1 LAST TOLERANCE 1%
J 0
(10500 5575);
DISPLAY 0.638298 (10500 5575);
FORCEPROP 1 LAST VALUE 10K
J 2
(10475 5575);
DISPLAY 0.638298 (10475 5575);
FORCEPROP 1 LAST $LOCATION R4494
J 0
(10025 5575);
DISPLAY 0.638298 (10025 5575);
FORCEPROP 1 LASTPIN (10150 5575) $PN 1
J 0
(10162 5587);
DISPLAY 0.787234 (10162 5587);
PAINT MONO (10162 5587);
FORCEPROP 1 LASTPIN (10350 5575) $PN 2
J 0
(10312 5587);
DISPLAY 0.787234 (10312 5587);
PAINT MONO (10312 5587);
FORCEPROP 1 LAST PACK_TYPE 0402LF
J 0
(10500 5425);
DISPLAY 0.978723 (10500 5425);
DISPLAY INVISIBLE (10500 5425);
FORCEPROP 1 LAST WATTAGE 1/16W
J 2
(10225 5425);
DISPLAY 0.978723 (10225 5425);
DISPLAY INVISIBLE (10225 5425);
FORCEPROP 2 LAST CDS_LIB pure_quanta
J 0
(10250 5575);
DISPLAY INVISIBLE (10250 5575);
FORCEPROP 1 LAST PATH I69
J 0
(10200 5725);
DISPLAY 0.978723 (10200 5725);
PAINT WHITE (10200 5725);
DISPLAY INVISIBLE (10200 5725);
FORCEPROP 0 LAST CDS_LOCATION R4494
J 0
(10600 5625);
DISPLAY 1.021277 (10600 5625);
DISPLAY INVISIBLE (10600 5625);
FORCEPROP 0 LAST $SEC 1
J 0
(10600 5625);
DISPLAY 0.680851 (10600 5625);
PAINT MONO (10600 5625);
DISPLAY INVISIBLE (10600 5625);
FORCEPROP 0 LAST CDS_SEC 1
J 0
(10600 5625);
DISPLAY 1.021277 (10600 5625);
DISPLAY INVISIBLE (10600 5625);
FORCEADD UNIVERSAL_POWER..1
(4325 8450);
FORCEPROP 3 LASTPIN (4325 8400) SIG_NAME P3V3\g
J 0
(4335 8410);
DISPLAY 0.659574 (4335 8410);
PAINT MONO (4335 8410);
DISPLAY INVISIBLE (4335 8410);
FORCEPROP 1 LAST HDL_POWER P3V3
J 1
(4325 8500);
DISPLAY 0.872340 (4325 8500);
PAINT GREEN (4325 8500);
FORCEPROP 1 LAST PATH I7
J 0
(4375 8475);
DISPLAY 0.872340 (4375 8475);
PAINT AQUA (4375 8475);
DISPLAY INVISIBLE (4375 8475);
FORCEPROP 2 LAST CDS_LIB logical_power
J 0
(4325 8450);
DISPLAY INVISIBLE (4325 8450);
FORCEADD UNIVERSAL_POWER..1
(12775 5875);
FORCEPROP 3 LASTPIN (12775 5825) SIG_NAME P3V3\g
J 0
(12785 5835);
DISPLAY 0.659574 (12785 5835);
PAINT MONO (12785 5835);
DISPLAY INVISIBLE (12785 5835);
FORCEPROP 1 LAST HDL_POWER P3V3
J 1
(12775 5925);
DISPLAY 0.872340 (12775 5925);
PAINT GREEN (12775 5925);
FORCEPROP 2 LAST CDS_LIB logical_power
J 0
(12775 5875);
DISPLAY INVISIBLE (12775 5875);
FORCEPROP 1 LAST PATH I70
J 0
(12825 5900);
DISPLAY 0.872340 (12825 5900);
PAINT AQUA (12825 5900);
DISPLAY INVISIBLE (12825 5900);
FORCEADD Q_CAP..1
(9975 7825);
FORCEPROP 1 LAST PART_NUMBER CH4104K1B00
J 0
(10025 7675);
DISPLAY 0.404255 (10025 7675);
DISPLAY INVISIBLE (10025 7675);
FORCEPROP 1 LAST VOLTAGE 25V
J 0
(10025 7825);
DISPLAY 0.510638 (10025 7825);
FORCEPROP 1 LAST VALUE 0.1UF
J 0
(10025 7875);
DISPLAY 0.510638 (10025 7875);
FORCEPROP 1 LAST TOLERANCE 10%
J 0
(10025 7775);
DISPLAY 0.510638 (10025 7775);
FORCEPROP 1 LAST MATERIAL X7R
J 0
(10025 7725);
DISPLAY 0.510638 (10025 7725);
FORCEPROP 1 LAST PACK_TYPE 0402
J 0
(10025 7625);
DISPLAY 0.510638 (10025 7625);
FORCEPROP 1 LAST $LOCATION C2339
J 0
(10025 7925);
DISPLAY 0.978723 (10025 7925);
FORCEPROP 1 LASTPIN (9975 7925) $PN 1
J 0
(9985 7905);
DISPLAY 0.787234 (9985 7905);
PAINT MONO (9985 7905);
FORCEPROP 1 LASTPIN (9975 7725) $PN 2
J 0
(9985 7705);
DISPLAY 0.787234 (9985 7705);
PAINT MONO (9985 7705);
FORCEPROP 2 LAST CDS_LIB pure_quanta
J 0
(9975 7825);
DISPLAY INVISIBLE (9975 7825);
FORCEPROP 1 LAST PATH I71
J 0
(10025 7975);
DISPLAY 0.978723 (10025 7975);
PAINT WHITE (10025 7975);
DISPLAY INVISIBLE (10025 7975);
FORCEPROP 2 LAST CDS_LOCATION C2339
J 0
(10025 8025);
DISPLAY 1.021277 (10025 8025);
DISPLAY INVISIBLE (10025 8025);
FORCEPROP 2 LAST $SEC 1
J 0
(10025 8025);
DISPLAY 0.680851 (10025 8025);
PAINT MONO (10025 8025);
DISPLAY INVISIBLE (10025 8025);
FORCEPROP 2 LAST CDS_SEC 1
J 0
(10025 8025);
DISPLAY 1.021277 (10025 8025);
DISPLAY INVISIBLE (10025 8025);
FORCEADD OFFPAGE..1
R 2
(12150 5675);
FORCEPROP 2 LAST $XR0 215 
J 0
(12336 5675);
DISPLAY 0.638298 (12336 5675);
PAINT MONO (12336 5675);
FORCEPROP 2 LAST CDS_LIB standard
J 0
(12150 5675);
DISPLAY INVISIBLE (12150 5675);
FORCEPROP 1 LAST COMMENT_BODY TRUE
J 2
(12025 5575);
DISPLAY 1.170213 (12025 5575);
PAINT GREEN (12025 5575);
DISPLAY INVISIBLE (12025 5575);
FORCEPROP 1 LAST OFFPAGE TRUE
J 2
(11825 5550);
DISPLAY 1.170213 (11825 5550);
PAINT GREEN (11825 5550);
DISPLAY INVISIBLE (11825 5550);
FORCEPROP 2 LAST PATH I72
J 0
(12475 5725);
DISPLAY 1.021277 (12475 5725);
DISPLAY INVISIBLE (12475 5725);
FORCEADD OFFPAGE..1
R 2
(12150 5625);
FORCEPROP 2 LAST $XR0 215 
J 0
(12336 5625);
DISPLAY 0.638298 (12336 5625);
PAINT MONO (12336 5625);
FORCEPROP 1 LAST OFFPAGE TRUE
J 2
(11825 5500);
DISPLAY 1.170213 (11825 5500);
PAINT GREEN (11825 5500);
DISPLAY INVISIBLE (11825 5500);
FORCEPROP 1 LAST COMMENT_BODY TRUE
J 2
(12025 5525);
DISPLAY 1.170213 (12025 5525);
PAINT GREEN (12025 5525);
DISPLAY INVISIBLE (12025 5525);
FORCEPROP 2 LAST CDS_LIB standard
J 0
(12150 5625);
DISPLAY INVISIBLE (12150 5625);
FORCEPROP 2 LAST PATH I73
J 0
(12475 5675);
DISPLAY 1.021277 (12475 5675);
DISPLAY INVISIBLE (12475 5675);
FORCEADD Q_RES..1
(10250 5725);
FORCEPROP 1 LAST PART_NUMBER CS03322FB03
J 0
(10100 5800);
DISPLAY 0.638298 (10100 5800);
DISPLAY INVISIBLE (10100 5800);
FORCEPROP 1 LAST MATERIAL CHIP
J 0
(10600 5725);
DISPLAY 0.638298 (10600 5725);
FORCEPROP 1 LAST TOLERANCE 1%
J 0
(10525 5725);
DISPLAY 0.638298 (10525 5725);
FORCEPROP 1 LAST VALUE 33.2
J 2
(10500 5725);
DISPLAY 0.638298 (10500 5725);
FORCEPROP 1 LAST LOCATION R4477
J 0
(10000 5725);
DISPLAY 0.638298 (10000 5725);
FORCEPROP 1 LASTPIN (10150 5725) $PN 1
J 0
(10162 5737);
DISPLAY 0.787234 (10162 5737);
PAINT MONO (10162 5737);
FORCEPROP 1 LASTPIN (10350 5725) $PN 2
J 0
(10312 5737);
DISPLAY 0.787234 (10312 5737);
PAINT MONO (10312 5737);
FORCEPROP 2 LAST CDS_LIB pure_quanta
J 0
(10250 5725);
DISPLAY INVISIBLE (10250 5725);
FORCEPROP 1 LAST PATH I74
J 0
(10200 5875);
DISPLAY 0.978723 (10200 5875);
PAINT WHITE (10200 5875);
DISPLAY INVISIBLE (10200 5875);
FORCEPROP 1 LAST WATTAGE 1/16W
J 2
(10450 5850);
DISPLAY 0.638298 (10450 5850);
DISPLAY INVISIBLE (10450 5850);
FORCEPROP 1 LAST PACK_TYPE 0402LF
J 0
(10100 5850);
DISPLAY 0.638298 (10100 5850);
DISPLAY INVISIBLE (10100 5850);
FORCEPROP 0 LAST $SEC 1
J 0
(10600 5775);
DISPLAY 0.680851 (10600 5775);
PAINT MONO (10600 5775);
DISPLAY INVISIBLE (10600 5775);
FORCEPROP 0 LAST CDS_SEC 1
J 0
(10600 5775);
DISPLAY 1.021277 (10600 5775);
DISPLAY INVISIBLE (10600 5775);
FORCEADD Q_RES..1
(10250 5675);
FORCEPROP 1 LAST PART_NUMBER CS03322FB03
J 0
(10100 5750);
DISPLAY 0.638298 (10100 5750);
DISPLAY INVISIBLE (10100 5750);
FORCEPROP 1 LAST TOLERANCE 1%
J 0
(10525 5675);
DISPLAY 0.638298 (10525 5675);
FORCEPROP 1 LAST MATERIAL CHIP
J 0
(10600 5675);
DISPLAY 0.638298 (10600 5675);
FORCEPROP 1 LAST VALUE 33.2
J 2
(10500 5675);
DISPLAY 0.638298 (10500 5675);
FORCEPROP 1 LAST LOCATION R4478
J 0
(10000 5675);
DISPLAY 0.638298 (10000 5675);
FORCEPROP 1 LASTPIN (10150 5675) $PN 1
J 0
(10162 5687);
DISPLAY 0.787234 (10162 5687);
PAINT MONO (10162 5687);
FORCEPROP 1 LASTPIN (10350 5675) $PN 2
J 0
(10312 5687);
DISPLAY 0.787234 (10312 5687);
PAINT MONO (10312 5687);
FORCEPROP 1 LAST PATH I75
J 0
(10200 5825);
DISPLAY 0.978723 (10200 5825);
PAINT WHITE (10200 5825);
DISPLAY INVISIBLE (10200 5825);
FORCEPROP 2 LAST CDS_LIB pure_quanta
J 0
(10250 5675);
DISPLAY INVISIBLE (10250 5675);
FORCEPROP 1 LAST WATTAGE 1/16W
J 2
(10450 5800);
DISPLAY 0.638298 (10450 5800);
DISPLAY INVISIBLE (10450 5800);
FORCEPROP 1 LAST PACK_TYPE 0402LF
J 0
(10100 5800);
DISPLAY 0.638298 (10100 5800);
DISPLAY INVISIBLE (10100 5800);
FORCEPROP 0 LAST $SEC 1
J 0
(10600 5725);
DISPLAY 0.680851 (10600 5725);
PAINT MONO (10600 5725);
DISPLAY INVISIBLE (10600 5725);
FORCEPROP 0 LAST CDS_SEC 1
J 0
(10600 5725);
DISPLAY 1.021277 (10600 5725);
DISPLAY INVISIBLE (10600 5725);
FORCEADD Q_RES..1
(10250 5625);
FORCEPROP 1 LAST PART_NUMBER CS03322FB03
J 0
(10100 5700);
DISPLAY 0.638298 (10100 5700);
DISPLAY INVISIBLE (10100 5700);
FORCEPROP 1 LAST TOLERANCE 1%
J 0
(10525 5625);
DISPLAY 0.638298 (10525 5625);
FORCEPROP 1 LAST MATERIAL CHIP
J 0
(10600 5625);
DISPLAY 0.638298 (10600 5625);
FORCEPROP 1 LAST VALUE 33.2
J 2
(10500 5625);
DISPLAY 0.638298 (10500 5625);
FORCEPROP 1 LAST LOCATION R4479
J 0
(10000 5625);
DISPLAY 0.638298 (10000 5625);
FORCEPROP 1 LASTPIN (10150 5625) $PN 1
J 0
(10162 5637);
DISPLAY 0.787234 (10162 5637);
PAINT MONO (10162 5637);
FORCEPROP 1 LASTPIN (10350 5625) $PN 2
J 0
(10312 5637);
DISPLAY 0.787234 (10312 5637);
PAINT MONO (10312 5637);
FORCEPROP 1 LAST PATH I76
J 0
(10200 5775);
DISPLAY 0.978723 (10200 5775);
PAINT WHITE (10200 5775);
DISPLAY INVISIBLE (10200 5775);
FORCEPROP 1 LAST PACK_TYPE 0402LF
J 0
(10100 5750);
DISPLAY 0.638298 (10100 5750);
DISPLAY INVISIBLE (10100 5750);
FORCEPROP 1 LAST WATTAGE 1/16W
J 2
(10450 5750);
DISPLAY 0.638298 (10450 5750);
DISPLAY INVISIBLE (10450 5750);
FORCEPROP 2 LAST CDS_LIB pure_quanta
J 0
(10250 5625);
DISPLAY INVISIBLE (10250 5625);
FORCEPROP 0 LAST $SEC 1
J 0
(10600 5675);
DISPLAY 0.680851 (10600 5675);
PAINT MONO (10600 5675);
DISPLAY INVISIBLE (10600 5675);
FORCEPROP 0 LAST CDS_SEC 1
J 0
(10600 5675);
DISPLAY 1.021277 (10600 5675);
DISPLAY INVISIBLE (10600 5675);
FORCEADD Q_RES..2
(11400 6125);
FORCEPROP 1 LAST PART_NUMBER CS31002FB08
J 0
(11440 6000);
DISPLAY 0.510638 (11440 6000);
DISPLAY INVISIBLE (11440 6000);
FORCEPROP 1 LAST TOLERANCE 1%
J 0
(11445 6150);
DISPLAY 0.510638 (11445 6150);
FORCEPROP 1 LAST WATTAGE 1/16W
J 0
(11440 6100);
DISPLAY 0.510638 (11440 6100);
FORCEPROP 1 LAST VALUE 10K
J 0
(11445 6200);
DISPLAY 0.510638 (11445 6200);
FORCEPROP 1 LAST MATERIAL CHIP
J 0
(11440 6050);
DISPLAY 0.510638 (11440 6050);
FORCEPROP 1 LAST PACK_TYPE 0402LF
J 0
(11450 6000);
DISPLAY 0.510638 (11450 6000);
FORCEPROP 1 LAST $LOCATION R4518
J 0
(11445 6250);
DISPLAY 0.638298 (11445 6250);
FORCEPROP 1 LASTPIN (11400 6225) $PN 1
J 0
(11405 6187);
DISPLAY 0.787234 (11405 6187);
PAINT MONO (11405 6187);
FORCEPROP 1 LASTPIN (11400 6025) $PN 2
J 0
(11405 6035);
DISPLAY 0.787234 (11405 6035);
PAINT MONO (11405 6035);
FORCEPROP 2 LAST CDS_LIB pure_quanta
J 0
(11400 6125);
DISPLAY INVISIBLE (11400 6125);
FORCEPROP 1 LAST PATH I77
J 0
(11450 6300);
DISPLAY 0.978723 (11450 6300);
PAINT WHITE (11450 6300);
DISPLAY INVISIBLE (11450 6300);
FORCEPROP 0 LAST CDS_LOCATION R4518
J 0
(11450 6300);
DISPLAY 1.021277 (11450 6300);
DISPLAY INVISIBLE (11450 6300);
FORCEPROP 0 LAST $SEC 1
J 0
(11450 6300);
DISPLAY 0.680851 (11450 6300);
PAINT MONO (11450 6300);
DISPLAY INVISIBLE (11450 6300);
FORCEPROP 0 LAST CDS_SEC 1
J 0
(11450 6300);
DISPLAY 1.021277 (11450 6300);
DISPLAY INVISIBLE (11450 6300);
FORCEADD Q_RES..2
(11625 6125);
FORCEPROP 1 LAST PART_NUMBER CS31002FB08
J 0
(11665 6000);
DISPLAY 0.510638 (11665 6000);
DISPLAY INVISIBLE (11665 6000);
FORCEPROP 1 LAST TOLERANCE 1%
J 0
(11670 6150);
DISPLAY 0.510638 (11670 6150);
FORCEPROP 1 LAST PACK_TYPE 0402LF
J 0
(11675 6000);
DISPLAY 0.510638 (11675 6000);
FORCEPROP 1 LAST MATERIAL CHIP
J 0
(11665 6050);
DISPLAY 0.510638 (11665 6050);
FORCEPROP 1 LAST VALUE 10K
J 0
(11670 6200);
DISPLAY 0.510638 (11670 6200);
FORCEPROP 1 LAST WATTAGE 1/16W
J 0
(11665 6100);
DISPLAY 0.510638 (11665 6100);
FORCEPROP 1 LAST $LOCATION R4519
J 0
(11670 6250);
DISPLAY 0.638298 (11670 6250);
FORCEPROP 1 LASTPIN (11625 6225) $PN 1
J 0
(11630 6187);
DISPLAY 0.787234 (11630 6187);
PAINT MONO (11630 6187);
FORCEPROP 1 LASTPIN (11625 6025) $PN 2
J 0
(11630 6035);
DISPLAY 0.787234 (11630 6035);
PAINT MONO (11630 6035);
FORCEPROP 1 LAST PATH I78
J 0
(11675 6300);
DISPLAY 0.978723 (11675 6300);
PAINT WHITE (11675 6300);
DISPLAY INVISIBLE (11675 6300);
FORCEPROP 2 LAST CDS_LIB pure_quanta
J 0
(11625 6125);
DISPLAY INVISIBLE (11625 6125);
FORCEPROP 0 LAST CDS_LOCATION R4519
J 0
(11675 6300);
DISPLAY 1.021277 (11675 6300);
DISPLAY INVISIBLE (11675 6300);
FORCEPROP 0 LAST $SEC 1
J 0
(11675 6300);
DISPLAY 0.680851 (11675 6300);
PAINT MONO (11675 6300);
DISPLAY INVISIBLE (11675 6300);
FORCEPROP 0 LAST CDS_SEC 1
J 0
(11675 6300);
DISPLAY 1.021277 (11675 6300);
DISPLAY INVISIBLE (11675 6300);
FORCEADD Q_RES..2
(11825 6125);
FORCEPROP 1 LAST PART_NUMBER CS31002FB08
J 0
(11865 6000);
DISPLAY 0.510638 (11865 6000);
DISPLAY INVISIBLE (11865 6000);
FORCEPROP 1 LAST TOLERANCE 1%
J 0
(11870 6150);
DISPLAY 0.510638 (11870 6150);
FORCEPROP 1 LAST WATTAGE 1/16W
J 0
(11865 6100);
DISPLAY 0.510638 (11865 6100);
FORCEPROP 1 LAST MATERIAL CHIP
J 0
(11865 6050);
DISPLAY 0.510638 (11865 6050);
FORCEPROP 1 LAST PACK_TYPE 0402LF
J 0
(11865 5950);
DISPLAY 0.510638 (11865 5950);
FORCEPROP 1 LAST VALUE 10K
J 0
(11870 6200);
DISPLAY 0.510638 (11870 6200);
FORCEPROP 1 LAST $LOCATION R4520
J 0
(11870 6250);
DISPLAY 0.638298 (11870 6250);
FORCEPROP 1 LASTPIN (11825 6225) $PN 1
J 0
(11830 6187);
DISPLAY 0.787234 (11830 6187);
PAINT MONO (11830 6187);
FORCEPROP 1 LASTPIN (11825 6025) $PN 2
J 0
(11830 6035);
DISPLAY 0.787234 (11830 6035);
PAINT MONO (11830 6035);
FORCEPROP 1 LAST PATH I79
J 0
(11875 6300);
DISPLAY 0.978723 (11875 6300);
PAINT WHITE (11875 6300);
DISPLAY INVISIBLE (11875 6300);
FORCEPROP 2 LAST CDS_LIB pure_quanta
J 0
(11825 6125);
DISPLAY INVISIBLE (11825 6125);
FORCEPROP 0 LAST CDS_LOCATION R4520
J 0
(11875 6300);
DISPLAY 1.021277 (11875 6300);
DISPLAY INVISIBLE (11875 6300);
FORCEPROP 0 LAST $SEC 1
J 0
(11875 6300);
DISPLAY 0.680851 (11875 6300);
PAINT MONO (11875 6300);
DISPLAY INVISIBLE (11875 6300);
FORCEPROP 0 LAST CDS_SEC 1
J 0
(11875 6300);
DISPLAY 1.021277 (11875 6300);
DISPLAY INVISIBLE (11875 6300);
FORCEADD UNIVERSAL_GND..1
(6375 7800);
FORCEPROP 3 LASTPIN (6375 7850) SIG_NAME GND\g
J 0
(6385 7860);
DISPLAY 0.659574 (6385 7860);
PAINT MONO (6385 7860);
DISPLAY INVISIBLE (6385 7860);
FORCEPROP 2 LAST CDS_LIB logical_power
J 0
(6375 7800);
DISPLAY INVISIBLE (6375 7800);
FORCEPROP 1 LAST PATH I8
J 0
(6450 7800);
DISPLAY 0.872340 (6450 7800);
PAINT AQUA (6450 7800);
DISPLAY INVISIBLE (6450 7800);
FORCEPROP 1 LAST HDL_POWER GND
J 1
(6400 7725);
DISPLAY 0.872340 (6400 7725);
PAINT GREEN (6400 7725);
DISPLAY INVISIBLE (6400 7725);
FORCEADD UNIVERSAL_POWER..1
(11825 6575);
FORCEPROP 3 LASTPIN (11825 6525) SIG_NAME P3V3\g
J 0
(11835 6535);
DISPLAY 0.659574 (11835 6535);
PAINT MONO (11835 6535);
DISPLAY INVISIBLE (11835 6535);
FORCEPROP 1 LAST HDL_POWER P3V3
J 1
(11825 6625);
DISPLAY 0.872340 (11825 6625);
PAINT GREEN (11825 6625);
FORCEPROP 1 LAST PATH I80
J 0
(11875 6600);
DISPLAY 0.872340 (11875 6600);
PAINT AQUA (11875 6600);
DISPLAY INVISIBLE (11875 6600);
FORCEPROP 2 LAST CDS_LIB logical_power
J 0
(11825 6575);
DISPLAY INVISIBLE (11825 6575);
FORCEADD Q_INDUCTOR..1
(4750 8375);
FORCEPROP 1 LAST PART_NUMBER CX601T05003
J 0
(4625 8485);
DISPLAY 0.723404 (4625 8485);
PAINT GREEN (4625 8485);
DISPLAY INVISIBLE (4625 8485);
FORCEPROP 1 LAST MATERIAL IND
J 0
(4625 8430);
DISPLAY 0.723404 (4625 8430);
PAINT GREEN (4625 8430);
FORCEPROP 2 LAST PACK_TYPE SMLF
J 0
(4625 8625);
DISPLAY 0.638298 (4625 8625);
FORCEPROP 2 LAST VALUE FCM2012KF-601T/0.5A
J 0
(4625 8575);
DISPLAY 0.638298 (4625 8575);
FORCEPROP 1 LAST LOCATION L19
J 0
(4625 8535);
DISPLAY 0.723404 (4625 8535);
PAINT GREEN (4625 8535);
FORCEPROP 0 LASTPIN (4650 8350) $PN 1
J 2
(4640 8360);
DISPLAY 0.680851 (4640 8360);
PAINT MONO (4640 8360);
FORCEPROP 0 LASTPIN (4850 8350) $PN 2
J 0
(4860 8360);
DISPLAY 0.680851 (4860 8360);
PAINT MONO (4860 8360);
FORCEPROP 2 LAST CDS_LIB pure_quanta
J 0
(4750 8375);
DISPLAY INVISIBLE (4750 8375);
FORCEPROP 1 LAST PATH I81
J 0
(4825 8430);
DISPLAY 0.723404 (4825 8430);
PAINT GREEN (4825 8430);
DISPLAY INVISIBLE (4825 8430);
FORCEPROP 1 LAST NEEDS_NO_SIZE TRUE
J 0
(4750 8375);
DISPLAY 0.468085 (4750 8375);
PAINT GREEN (4750 8375);
DISPLAY INVISIBLE (4750 8375);
FORCEPROP 0 LAST $SEC 1
J 0
(4625 8675);
DISPLAY 0.680851 (4625 8675);
PAINT MONO (4625 8675);
DISPLAY INVISIBLE (4625 8675);
FORCEPROP 0 LAST CDS_SEC 1
J 0
(4625 8675);
DISPLAY 1.021277 (4625 8675);
DISPLAY INVISIBLE (4625 8675);
FORCEADD Q_INDUCTOR..1
(8075 8050);
FORCEPROP 1 LAST PART_NUMBER CX601T05003
J 0
(7950 8160);
DISPLAY 0.723404 (7950 8160);
PAINT GREEN (7950 8160);
DISPLAY INVISIBLE (7950 8160);
FORCEPROP 2 LAST PACK_TYPE SMLF
J 0
(7950 8300);
DISPLAY 0.638298 (7950 8300);
FORCEPROP 1 LAST MATERIAL IND
J 0
(7950 8105);
DISPLAY 0.723404 (7950 8105);
PAINT GREEN (7950 8105);
FORCEPROP 2 LAST VALUE FCM2012KF-601T/0.5A
J 0
(7950 8250);
DISPLAY 0.638298 (7950 8250);
FORCEPROP 1 LAST LOCATION L20
J 0
(7950 8210);
DISPLAY 0.723404 (7950 8210);
PAINT GREEN (7950 8210);
FORCEPROP 0 LASTPIN (7975 8025) $PN 1
J 2
(7965 8035);
DISPLAY 0.680851 (7965 8035);
PAINT MONO (7965 8035);
FORCEPROP 0 LASTPIN (8175 8025) $PN 2
J 0
(8185 8035);
DISPLAY 0.680851 (8185 8035);
PAINT MONO (8185 8035);
FORCEPROP 1 LAST NEEDS_NO_SIZE TRUE
J 0
(8075 8050);
DISPLAY 0.468085 (8075 8050);
PAINT GREEN (8075 8050);
DISPLAY INVISIBLE (8075 8050);
FORCEPROP 1 LAST PATH I82
J 0
(8150 8105);
DISPLAY 0.723404 (8150 8105);
PAINT GREEN (8150 8105);
DISPLAY INVISIBLE (8150 8105);
FORCEPROP 2 LAST CDS_LIB pure_quanta
J 0
(8075 8050);
DISPLAY INVISIBLE (8075 8050);
FORCEPROP 0 LAST $SEC 1
J 0
(7950 8350);
DISPLAY 0.680851 (7950 8350);
PAINT MONO (7950 8350);
DISPLAY INVISIBLE (7950 8350);
FORCEPROP 0 LAST CDS_SEC 1
J 0
(7950 8350);
DISPLAY 1.021277 (7950 8350);
DISPLAY INVISIBLE (7950 8350);
FORCEADD DNS..2
(7275 3650);
PAINT RED (7275 3650);
FORCEPROP 1 LAST COMMENT_BODY TRUE
R 1
J 0
(7350 3425);
DISPLAY 0.872340 (7350 3425);
PAINT GREEN (7350 3425);
DISPLAY INVISIBLE (7350 3425);
FORCEPROP 2 LAST CDS_LIB mstr_misc
J 0
(7275 3650);
DISPLAY INVISIBLE (7275 3650);
FORCEADD QUANTA_TITLE_BLOCK_C..1
(13275 2600);
FORCEPROP 0 LAST CDS_CON_LAST_MODIFIED Fri Aug 25 14:03:27 2023
J 0
(11390 2615);
PAINT MONO (11390 2615);
DISPLAY INVISIBLE (11390 2615);
FORCEPROP 2 LAST CUSTOM_TXT_CDS <XR_PAGE_TITLE>
J 0
(5385 7850);
DISPLAY 0.638298 (5385 7850);
PAINT PINK (5385 7850);
DISPLAY INVISIBLE (5385 7850);
FORCEPROP 2 LAST CUSTOM_TXT_CDS <CON_LAST_MODIFIED>
J 0
(11390 2615);
DISPLAY 0.978723 (11390 2615);
FORCEPROP 2 LAST CUSTOM_TXT_CDS <Q_NUMBER>
J 0
(11872 2703);
DISPLAY 1.212766 (11872 2703);
FORCEPROP 1 LAST CUSTOM_TXT_CDS <NAME_2>
J 0
(10100 2650);
FORCEPROP 1 LAST CUSTOM_TXT_CDS <NAME_1>
J 0
(10100 2775);
FORCEPROP 1 LAST CUSTOM_TXT_CDS <Q_PROJ>
J 0
(10893 2702);
DISPLAY 1.212766 (10893 2702);
FORCEPROP 1 LAST CUSTOM_TXT_CDS <Q_REV>
J 0
(13091 2703);
DISPLAY 1.212766 (13091 2703);
FORCEPROP 1 LAST CUSTOM_TXT_CDS <CON_PAGE_NUM> OF <CON_TOTAL_PAGES>
J 0
(12829 2618);
DISPLAY 0.978723 (12829 2618);
FORCEPROP 1 LAST Q_TITLE CLK - 9ZXL045 CLK BUFFER
J 0
(3959 2651);
DISPLAY 1.957447 (3959 2651);
PAINT GREEN (3959 2651);
FORCEPROP 1 LAST Q_DEPT 
J 1
(9512 2649);
DISPLAY 1.957447 (9512 2649);
PAINT GREEN (9512 2649);
FORCEPROP 2 LAST CDS_XR_PAGE_TITLE CR-211 : @S9S_MB_2U_LIB.S9S_MB_2U(SCH_1):PAGE211
J 0
(5385 7850);
DISPLAY 0.638298 (5385 7850);
PAINT PINK (5385 7850);
DISPLAY INVISIBLE (5385 7850);
FORCEPROP 2 LAST PAGE_BORDER TRUE
J 0
(5385 7850);
DISPLAY 0.638298 (5385 7850);
PAINT PINK (5385 7850);
DISPLAY INVISIBLE (5385 7850);
FORCEPROP 1 LAST CDS_LMAN_SYM_OUTLINE -9475,6775,100,-125
J 0
(13275 2600);
DISPLAY 0.468085 (13275 2600);
PAINT GREEN (13275 2600);
DISPLAY INVISIBLE (13275 2600);
FORCEPROP 2 LAST CDS_LIB pure_quanta
J 0
(13275 2600);
PAINT MONO (13275 2600);
DISPLAY INVISIBLE (13275 2600);
FORCEPROP 1 LAST COMMENT_BODY TRUE
J 0
(13287 2587);
DISPLAY 0.978723 (13287 2587);
PAINT GREEN (13287 2587);
DISPLAY INVISIBLE (13287 2587);
WIRE 16 -1 (6375 8375)(6375 8350);
WIRE 16 -1 (7750 6625)(7750 6850);
WIRE 16 -1 (7750 6575)(7750 6625);
WIRE 16 -1 (8050 6625)(7750 6625);
WIRE 16 -1 (7350 6325)(7350 6550);
WIRE 16 -1 (8050 6325)(7350 6325);
WIRE 16 -1 (11825 6450)(11825 6525);
WIRE 16 -1 (11625 6450)(11825 6450);
WIRE 16 -1 (11825 6450)(11825 6225);
WIRE 16 -1 (12775 5825)(12775 5575);
WIRE 16 -1 (6400 7575)(6400 7525);
WIRE 16 -1 (7275 4400)(7275 4200);
WIRE 16 -1 (4325 8400)(4325 8350);
WIRE 16 -1 (9975 8125)(9975 8025);
WIRE 16 -1 (9625 6625)(9625 6850);
WIRE 16 -1 (9300 6625)(9625 6625);
WIRE 16 -1 (7625 8100)(7625 8025);
WIRE 16 -1 (9275 4350)(9275 4200);
WIRE 16 -1 (6400 7050)(6400 7150);
WIRE 16 -1 (6375 7850)(6375 7950);
WIRE 16 -1 (7275 3475)(7275 3575);
WIRE 16 -1 (9275 3425)(9275 3525);
WIRE 16 -1 (9500 5125)(9500 5375);
WIRE 16 -1 (9975 7525)(9975 7600);
WIRE 16 -1 (8175 8025)(8600 8025);
WIRE 16 -1 (8600 7925)(8600 8025);
WIRE 16 -1 (8950 8025)(8600 8025);
WIRE 16 -1 (8950 7925)(8950 8025);
WIRE 16 -1 (8950 8025)(9200 8025);
WIRE 16 -1 (9200 7925)(9200 8025);
WIRE 16 -1 (9200 8025)(9450 8025);
WIRE 16 -1 (9450 7925)(9450 8025);
WIRE 16 -1 (9700 8025)(9450 8025);
WIRE 16 -1 (9700 8025)(9700 7925);
WIRE 16 -1 (9975 8025)(9700 8025);
WIRE 16 -1 (9975 8025)(9975 7925);
WIRE 16 -1 (7625 8025)(7975 8025);
WIRE 16 -1 (4850 8350)(5350 8350);
FORCEPROP 2 LAST SIG_NAME P3V3_9ZXL045
J 0
(4965 8360);
DISPLAY 0.638298 (4965 8360);
PAINT WHITE (4965 8360);
WIRE 16 -1 (5500 8350)(5350 8350);
WIRE 16 -1 (5350 7525)(5550 7525);
WIRE 16 -1 (5350 7525)(5350 8350);
WIRE 16 -1 (4650 8350)(4325 8350);
WIRE 16 -1 (8050 6025)(7050 6025);
FORCEPROP 2 LAST SIG_NAME CLK_9ZXL045_SADR0
J 0
(7115 6035);
DISPLAY 0.702128 (7115 6035);
PAINT WHITE (7115 6035);
WIRE 16 -1 (8050 5925)(7050 5925);
FORCEPROP 2 LAST SIG_NAME SMB_HOST_9ZXL045_3V3AUX_SDA
J 0
(7115 5935);
DISPLAY 0.702128 (7115 5935);
PAINT WHITE (7115 5935);
WIRE 16 -1 (8050 5875)(7050 5875);
FORCEPROP 2 LAST SIG_NAME SMB_HOST_9ZXL045_3V3AUX_SCL
J 0
(7115 5885);
DISPLAY 0.702128 (7115 5885);
PAINT WHITE (7115 5885);
WIRE 16 -1 (8050 5775)(6625 5775);
FORCEPROP 2 LAST SIG_NAME FM_9ZXL045_DEV_EN
J 0
(7140 5785);
DISPLAY 0.680851 (7140 5785);
PAINT WHITE (7140 5785);
WIRE 16 -1 (10625 6275)(9300 6275);
FORCEPROP 2 LAST SIG_NAME CLK_100M_SWB_R_DP
J 0
(9465 6285);
DISPLAY 0.702128 (9465 6285);
PAINT WHITE (9465 6285);
WIRE 16 -1 (10625 6175)(9300 6175);
FORCEPROP 2 LAST SIG_NAME CLK_100M_GPU_1_R_DP
J 0
(9465 6185);
DISPLAY 0.702128 (9465 6185);
PAINT WHITE (9465 6185);
WIRE 16 -1 (10625 6125)(9300 6125);
FORCEPROP 2 LAST SIG_NAME CLK_100M_GPU_1_R_DN
J 0
(9465 6135);
DISPLAY 0.702128 (9465 6135);
PAINT WHITE (9465 6135);
WIRE 16 -1 (10625 6225)(9300 6225);
FORCEPROP 2 LAST SIG_NAME CLK_100M_SWB_R_DN
J 0
(9465 6235);
DISPLAY 0.702128 (9465 6235);
PAINT WHITE (9465 6235);
WIRE 16 -1 (9975 6475)(9300 6475);
FORCEPROP 2 LAST SIG_NAME CLK_9ZXL045_HIBW
J 0
(9465 6485);
DISPLAY 0.553191 (9465 6485);
PAINT WHITE (9465 6485);
WIRE 16 -1 (11625 6225)(11625 6450);
WIRE 16 -1 (11400 6450)(11625 6450);
WIRE 16 -1 (11400 6225)(11400 6450);
WIRE 16 -1 (10350 5725)(11825 5725);
FORCEPROP 2 LAST SIG_NAME CLK_SWB_BUF2_OE_N
J 0
(10740 5735);
DISPLAY 0.680851 (10740 5735);
PAINT WHITE (10740 5735);
WIRE 16 -1 (11825 5725)(12100 5725);
WIRE 16 -1 (11825 6025)(11825 5725);
WIRE 16 -1 (11625 5675)(10350 5675);
FORCEPROP 2 LAST SIG_NAME CLK_GPU_1_OE_N
J 0
(10740 5685);
DISPLAY 0.680851 (10740 5685);
PAINT WHITE (10740 5685);
WIRE 16 -1 (11625 6025)(11625 5675);
WIRE 16 -1 (12100 5675)(11625 5675);
WIRE 16 -1 (11400 5625)(10350 5625);
FORCEPROP 2 LAST SIG_NAME CLK_GPU_2_OE_N
J 0
(10740 5635);
DISPLAY 0.680851 (10740 5635);
PAINT WHITE (10740 5635);
WIRE 16 -1 (11400 6025)(11400 5625);
WIRE 16 -1 (12100 5625)(11400 5625);
WIRE 16 -1 (10625 5925)(9300 5925);
FORCEPROP 2 LAST SIG_NAME TP_CLK_100M_BUF_DIF3_DN
J 0
(9465 5935);
DISPLAY 0.702128 (9465 5935);
PAINT WHITE (9465 5935);
WIRE 16 -1 (9300 5725)(10150 5725);
FORCEPROP 2 LAST SIG_NAME FM_9ZXL045_0_OE_N
J 0
(9465 5735);
DISPLAY 0.680851 (9465 5735);
PAINT WHITE (9465 5735);
WIRE 16 -1 (9300 5575)(10150 5575);
FORCEPROP 2 LAST SIG_NAME FM_9ZXL045_3_OE_N
J 0
(9465 5585);
DISPLAY 0.680851 (9465 5585);
PAINT WHITE (9465 5585);
WIRE 16 -1 (10350 5575)(12775 5575);
WIRE 16 -1 (9300 5675)(10150 5675);
FORCEPROP 2 LAST SIG_NAME FM_9ZXL045_1_OE_N
J 0
(9465 5685);
DISPLAY 0.680851 (9465 5685);
PAINT WHITE (9465 5685);
WIRE 16 -1 (9300 5625)(10150 5625);
FORCEPROP 2 LAST SIG_NAME FM_9ZXL045_2_OE_N
J 0
(9465 5635);
DISPLAY 0.680851 (9465 5635);
PAINT WHITE (9465 5635);
WIRE 16 -1 (10625 5975)(9300 5975);
FORCEPROP 2 LAST SIG_NAME TP_CLK_100M_BUF_DIF3_DP
J 0
(9465 5985);
DISPLAY 0.702128 (9465 5985);
PAINT WHITE (9465 5985);
WIRE 16 -1 (10625 6025)(9300 6025);
FORCEPROP 2 LAST SIG_NAME CLK_100M_GPU_2_R_DN
J 0
(9465 6035);
DISPLAY 0.702128 (9465 6035);
PAINT WHITE (9465 6035);
WIRE 16 -1 (10625 6075)(9300 6075);
FORCEPROP 2 LAST SIG_NAME CLK_100M_GPU_2_R_DP
J 0
(9465 6085);
DISPLAY 0.702128 (9465 6085);
PAINT WHITE (9465 6085);
WIRE 16 -1 (8050 6125)(7050 6125);
FORCEPROP 2 LAST SIG_NAME CLK_100M_GPU_SWB_REF_DN
J 0
(7115 6135);
DISPLAY 0.680851 (7115 6135);
PAINT WHITE (7115 6135);
WIRE 16 -1 (8050 6175)(7050 6175);
FORCEPROP 2 LAST SIG_NAME CLK_100M_GPU_SWB_REF_DP
J 0
(7115 6185);
DISPLAY 0.680851 (7115 6185);
PAINT WHITE (7115 6185);
WIRE 16 -1 (5700 8350)(6025 8350);
WIRE 16 -1 (6025 8350)(6025 8275);
WIRE 16 -1 (6025 8350)(6375 8350);
WIRE 16 -1 (6375 8350)(6375 8275);
WIRE 16 -1 (6375 7950)(6375 8075);
WIRE 16 -1 (6025 7950)(6375 7950);
WIRE 16 -1 (6025 8075)(6025 7950);
WIRE 16 -1 (6050 7275)(6050 7150);
WIRE 16 -1 (6050 7150)(6400 7150);
WIRE 16 -1 (6400 7150)(6400 7275);
WIRE 16 -1 (9975 7725)(9975 7600);
WIRE 16 -1 (9700 7600)(9700 7725);
WIRE 16 -1 (9975 7600)(9700 7600);
WIRE 16 -1 (9450 7600)(9700 7600);
WIRE 16 -1 (9450 7725)(9450 7600);
WIRE 16 -1 (9200 7725)(9200 7600);
WIRE 16 -1 (9450 7600)(9200 7600);
WIRE 16 -1 (8950 7600)(9200 7600);
WIRE 16 -1 (8950 7725)(8950 7600);
WIRE 16 -1 (8600 7600)(8950 7600);
WIRE 16 -1 (8600 7725)(8600 7600);
WIRE 16 -1 (9300 5375)(9500 5375);
WIRE 16 -1 (6400 7525)(6400 7475);
WIRE 16 -1 (6050 7475)(6050 7525);
WIRE 16 -1 (6050 7525)(6400 7525);
WIRE 16 -1 (5750 7525)(6050 7525);
WIRE 16 -1 (8050 6575)(7750 6575);
WIRE 16 -1 (7750 6525)(7750 6575);
WIRE 16 -1 (8050 6525)(7750 6525);
WIRE 16 -1 (7750 6475)(7750 6525);
WIRE 16 -1 (8050 6475)(7750 6475);
WIRE 16 -1 (7750 6425)(7750 6475);
WIRE 16 -1 (8050 6425)(7750 6425);
WIRE 16 -1 (8050 5675)(6625 5675);
FORCEPROP 2 LAST SIG_NAME NC_U314_FBOUT_N
J 0
(7140 5685);
DISPLAY 0.680851 (7140 5685);
PAINT WHITE (7140 5685);
WIRE 16 -1 (8050 5525)(6625 5525);
FORCEPROP 2 LAST SIG_NAME NC_U314_NC0
J 0
(7140 5535);
DISPLAY 0.680851 (7140 5535);
PAINT WHITE (7140 5535);
WIRE 16 -1 (8050 5475)(6625 5475);
FORCEPROP 2 LAST SIG_NAME NC_U314_NC1
J 0
(7140 5485);
DISPLAY 0.680851 (7140 5485);
PAINT WHITE (7140 5485);
WIRE 16 -1 (8050 5425)(6625 5425);
FORCEPROP 2 LAST SIG_NAME NC_U314_NC2
J 0
(7140 5435);
DISPLAY 0.680851 (7140 5435);
PAINT WHITE (7140 5435);
WIRE 16 -1 (8050 5375)(6625 5375);
FORCEPROP 2 LAST SIG_NAME NC_U314_NC3
J 0
(7140 5385);
DISPLAY 0.680851 (7140 5385);
PAINT WHITE (7140 5385);
WIRE 16 -1 (8050 5725)(6625 5725);
FORCEPROP 2 LAST SIG_NAME NC_U314_FBOUT
J 0
(7140 5735);
DISPLAY 0.680851 (7140 5735);
PAINT WHITE (7140 5735);
WIRE 16 -1 (9275 3875)(9275 3725);
WIRE 16 -1 (9275 4000)(9275 3875);
WIRE 16 -1 (9950 3875)(9275 3875);
FORCEPROP 2 LAST SIG_NAME CLK_9ZXL045_HIBW
J 0
(9340 3885);
DISPLAY 0.553191 (9340 3885);
PAINT WHITE (9340 3885);
WIRE 16 -1 (7275 4000)(7275 3875);
WIRE 16 -1 (7950 3875)(7275 3875);
FORCEPROP 2 LAST SIG_NAME CLK_9ZXL045_SADR0
J 0
(7340 3885);
DISPLAY 0.553191 (7340 3885);
PAINT WHITE (7340 3885);
WIRE 16 -1 (7275 3775)(7275 3875);
WIRE 16 -1 (6425 5775)(5600 5775);
FORCEPROP 2 LAST SIG_NAME FM_PLD_CLKS_DEV_EN
J 0
(5690 5785);
DISPLAY 0.680851 (5690 5785);
PAINT WHITE (5690 5785);
DOT 1 (7750 6525);
DOT 1 (6400 7150);
DOT 1 (9200 7600);
DOT 1 (8950 7600);
DOT 1 (9700 7600);
DOT 1 (9975 8025);
DOT 1 (9975 7600);
DOT 1 (9700 8025);
DOT 1 (7750 6575);
DOT 1 (7275 3875);
DOT 1 (9275 3875);
DOT 1 (7750 6625);
DOT 1 (7750 6475);
DOT 1 (9450 8025);
DOT 1 (9200 8025);
DOT 1 (8950 8025);
DOT 1 (8600 8025);
DOT 1 (9450 7600);
DOT 1 (6375 7950);
DOT 1 (6025 8350);
DOT 1 (5350 8350);
DOT 1 (6400 7525);
DOT 1 (6050 7525);
DOT 1 (6375 8350);
DOT 1 (11400 5625);
DOT 1 (11625 5675);
DOT 1 (11825 5725);
DOT 1 (11825 6450);
DOT 1 (11625 6450);
FORCENOTE
20211210 MODIFY FOR GT
(4050 9050) 0;
DISPLAY LEFT (4050 9050);
DISPLAY 2.510638 (4050 9050);
PAINT PINK (4050 9050);
FORCENOTE
9ZXL045 ADDRESS: 0XDE
(7850 4850) 0;
DISPLAY LEFT (7850 4850);
DISPLAY 1.595745 (7850 4850);
PAINT SKYBLUE (7850 4850);
QUIT
